FILE_TYPE = MACRO_DRAWING;
SET COLOR_WIRE YELLOW;
SET COLOR_PROP MONO;
SET COLOR_DOT WHITE;
SET COLOR_ARC YELLOW;
SET COLOR_BODY GREEN;
SET COLOR_NOTE MONO;
SET PROP_DISPLAY VALUE;
SET PAGE_NUMBER P139;
FORCEADD OFFPAGE..4
(-2625 4275);
FORCEPROP 2 LAST $XR0 141 
J 0
(-2439 4275);
DISPLAY 0.638298 (-2439 4275);
PAINT MONO (-2439 4275);
FORCEPROP 2 LAST CDS_LIB mstr_standard
J 0
(-2625 4275);
PAINT ORANGE (-2625 4275);
DISPLAY INVISIBLE (-2625 4275);
FORCEPROP 2 LAST PATH I101
J 0
(-2425 4350);
DISPLAY 1.021277 (-2425 4350);
PAINT ORANGE (-2425 4350);
DISPLAY INVISIBLE (-2425 4350);
FORCEPROP 1 LAST OFFPAGE TRUE
J 0
(-2300 4150);
DISPLAY 0.872340 (-2300 4150);
PAINT GREEN (-2300 4150);
DISPLAY INVISIBLE (-2300 4150);
FORCEPROP 1 LAST COMMENT_BODY TRUE
J 0
(-2650 4175);
DISPLAY 0.872340 (-2650 4175);
PAINT GREEN (-2650 4175);
DISPLAY INVISIBLE (-2650 4175);
FORCEADD OFFPAGE..4
(-2625 4225);
FORCEPROP 2 LAST $XR0 141 
J 0
(-2439 4225);
DISPLAY 0.638298 (-2439 4225);
PAINT MONO (-2439 4225);
FORCEPROP 2 LAST CDS_LIB mstr_standard
J 0
(-2625 4225);
PAINT ORANGE (-2625 4225);
DISPLAY INVISIBLE (-2625 4225);
FORCEPROP 2 LAST PATH I102
J 0
(-2425 4300);
DISPLAY 1.021277 (-2425 4300);
PAINT ORANGE (-2425 4300);
DISPLAY INVISIBLE (-2425 4300);
FORCEPROP 1 LAST OFFPAGE TRUE
J 0
(-2300 4100);
DISPLAY 0.872340 (-2300 4100);
PAINT GREEN (-2300 4100);
DISPLAY INVISIBLE (-2300 4100);
FORCEPROP 1 LAST COMMENT_BODY TRUE
J 0
(-2650 4125);
DISPLAY 0.872340 (-2650 4125);
PAINT GREEN (-2650 4125);
DISPLAY INVISIBLE (-2650 4125);
FORCEADD OFFPAGE..2
(-2625 4175);
FORCEPROP 2 LAST $XR0 141 
J 0
(-2436 4175);
DISPLAY 0.638298 (-2436 4175);
PAINT MONO (-2436 4175);
FORCEPROP 2 LAST CDS_LIB mstr_standard
J 0
(-2625 4175);
PAINT ORANGE (-2625 4175);
DISPLAY INVISIBLE (-2625 4175);
FORCEPROP 2 LAST PATH I103
J 0
(-2425 4250);
DISPLAY 1.021277 (-2425 4250);
PAINT ORANGE (-2425 4250);
DISPLAY INVISIBLE (-2425 4250);
FORCEPROP 1 LAST OFFPAGE TRUE
J 0
(-2300 4050);
DISPLAY 0.872340 (-2300 4050);
PAINT GREEN (-2300 4050);
DISPLAY INVISIBLE (-2300 4050);
FORCEPROP 1 LAST COMMENT_BODY TRUE
J 0
(-2670 4080);
DISPLAY 0.872340 (-2670 4080);
PAINT GREEN (-2670 4080);
DISPLAY INVISIBLE (-2670 4080);
FORCEADD OFFPAGE..2
(-2625 4125);
FORCEPROP 2 LAST $XR0 141 
J 0
(-2436 4125);
DISPLAY 0.638298 (-2436 4125);
PAINT MONO (-2436 4125);
FORCEPROP 2 LAST CDS_LIB mstr_standard
J 0
(-2625 4125);
PAINT ORANGE (-2625 4125);
DISPLAY INVISIBLE (-2625 4125);
FORCEPROP 2 LAST PATH I104
J 0
(-2425 4200);
DISPLAY 1.021277 (-2425 4200);
PAINT ORANGE (-2425 4200);
DISPLAY INVISIBLE (-2425 4200);
FORCEPROP 1 LAST OFFPAGE TRUE
J 0
(-2300 4000);
DISPLAY 0.872340 (-2300 4000);
PAINT GREEN (-2300 4000);
DISPLAY INVISIBLE (-2300 4000);
FORCEPROP 1 LAST COMMENT_BODY TRUE
J 0
(-2670 4030);
DISPLAY 0.872340 (-2670 4030);
PAINT GREEN (-2670 4030);
DISPLAY INVISIBLE (-2670 4030);
FORCEADD OFFPAGE..3
(-2625 4075);
FORCEPROP 2 LAST $XR0 141 
J 0
(-2411 4075);
DISPLAY 0.638298 (-2411 4075);
PAINT MONO (-2411 4075);
FORCEPROP 2 LAST CDS_LIB mstr_standard
J 0
(-2625 4075);
PAINT ORANGE (-2625 4075);
DISPLAY INVISIBLE (-2625 4075);
FORCEPROP 2 LAST PATH I105
J 0
(-2425 4150);
DISPLAY 1.021277 (-2425 4150);
PAINT ORANGE (-2425 4150);
DISPLAY INVISIBLE (-2425 4150);
FORCEPROP 1 LAST OFFPAGE TRUE
J 0
(-2300 3950);
DISPLAY 0.872340 (-2300 3950);
PAINT GREEN (-2300 3950);
DISPLAY INVISIBLE (-2300 3950);
FORCEPROP 1 LAST COMMENT_BODY TRUE
J 0
(-2675 3975);
DISPLAY 0.872340 (-2675 3975);
PAINT GREEN (-2675 3975);
DISPLAY INVISIBLE (-2675 3975);
FORCEADD OFFPAGE..3
(-2625 4025);
FORCEPROP 2 LAST $XR0 141 
J 0
(-2411 4025);
DISPLAY 0.638298 (-2411 4025);
PAINT MONO (-2411 4025);
FORCEPROP 2 LAST CDS_LIB mstr_standard
J 0
(-2625 4025);
PAINT ORANGE (-2625 4025);
DISPLAY INVISIBLE (-2625 4025);
FORCEPROP 2 LAST PATH I106
J 0
(-2425 4100);
DISPLAY 1.021277 (-2425 4100);
PAINT ORANGE (-2425 4100);
DISPLAY INVISIBLE (-2425 4100);
FORCEPROP 1 LAST OFFPAGE TRUE
J 0
(-2300 3900);
DISPLAY 0.872340 (-2300 3900);
PAINT GREEN (-2300 3900);
DISPLAY INVISIBLE (-2300 3900);
FORCEPROP 1 LAST COMMENT_BODY TRUE
J 0
(-2675 3925);
DISPLAY 0.872340 (-2675 3925);
PAINT GREEN (-2675 3925);
DISPLAY INVISIBLE (-2675 3925);
FORCEADD OFFPAGE..3
(-2625 3925);
FORCEPROP 2 LAST $XR0 141 
J 0
(-2411 3925);
DISPLAY 0.638298 (-2411 3925);
PAINT MONO (-2411 3925);
FORCEPROP 2 LAST CDS_LIB mstr_standard
J 0
(-2625 3925);
PAINT ORANGE (-2625 3925);
DISPLAY INVISIBLE (-2625 3925);
FORCEPROP 2 LAST PATH I107
J 0
(-2425 4000);
DISPLAY 1.021277 (-2425 4000);
PAINT ORANGE (-2425 4000);
DISPLAY INVISIBLE (-2425 4000);
FORCEPROP 1 LAST OFFPAGE TRUE
J 0
(-2300 3800);
DISPLAY 0.872340 (-2300 3800);
PAINT GREEN (-2300 3800);
DISPLAY INVISIBLE (-2300 3800);
FORCEPROP 1 LAST COMMENT_BODY TRUE
J 0
(-2675 3825);
DISPLAY 0.872340 (-2675 3825);
PAINT GREEN (-2675 3825);
DISPLAY INVISIBLE (-2675 3825);
FORCEADD OFFPAGE..3
(-2625 3975);
FORCEPROP 2 LAST $XR0 141 
J 0
(-2411 3975);
DISPLAY 0.638298 (-2411 3975);
PAINT MONO (-2411 3975);
FORCEPROP 2 LAST CDS_LIB mstr_standard
J 0
(-2625 3975);
PAINT ORANGE (-2625 3975);
DISPLAY INVISIBLE (-2625 3975);
FORCEPROP 2 LAST PATH I108
J 0
(-2425 4050);
DISPLAY 1.021277 (-2425 4050);
PAINT ORANGE (-2425 4050);
DISPLAY INVISIBLE (-2425 4050);
FORCEPROP 1 LAST OFFPAGE TRUE
J 0
(-2300 3850);
DISPLAY 0.872340 (-2300 3850);
PAINT GREEN (-2300 3850);
DISPLAY INVISIBLE (-2300 3850);
FORCEPROP 1 LAST COMMENT_BODY TRUE
J 0
(-2675 3875);
DISPLAY 0.872340 (-2675 3875);
PAINT GREEN (-2675 3875);
DISPLAY INVISIBLE (-2675 3875);
FORCEADD CRYSTAL..1
(-7525 1475);
FORCEPROP 0 LAST GROUP NI_I210&RJ45
J 0
(-7444 1413);
DISPLAY 0.638298 (-7444 1413);
PAINT BROWN (-7444 1413);
DISPLAY BOTH (-7444 1413);
FORCEPROP 1 LAST VALUE 25.000MHZ
J 1
(-7518 1536);
DISPLAY 0.617021 (-7518 1536);
PAINT SKYBLUE (-7518 1536);
FORCEPROP 1 LAST PART_NUMBER D71700-057
J 0
(-7725 1625);
DISPLAY 0.617021 (-7725 1625);
PAINT BLUE (-7725 1625);
FORCEPROP 1 LASTPIN (-7425 1475) $PN 3
J 0
(-7460 1485);
DISPLAY 0.617021 (-7460 1485);
PAINT AQUA (-7460 1485);
FORCEPROP 1 LAST LOCATION Y9E1
J 1
(-7520 1574);
DISPLAY 0.617021 (-7520 1574);
PAINT AQUA (-7520 1574);
FORCEPROP 1 LASTPIN (-7625 1475) $PN 1
J 2
(-7580 1485);
DISPLAY 0.617021 (-7580 1485);
PAINT AQUA (-7580 1485);
FORCEPROP 1 LAST MATERIAL IC
J 0
(-7536 1391);
DISPLAY 0.617021 (-7536 1391);
PAINT SKYBLUE (-7536 1391);
FORCEPROP 2 LAST CDS_LIB mstr_discrete
J 0
(-7525 1475);
PAINT ORANGE (-7525 1475);
DISPLAY INVISIBLE (-7525 1475);
FORCEPROP 1 LAST PACK_TYPE 2013
J 0
(-7537 1383);
DISPLAY 0.702128 (-7537 1383);
PAINT SKYBLUE (-7537 1383);
DISPLAY INVISIBLE (-7537 1383);
FORCEPROP 2 LAST ROOM NIC_SPRV
J 0
(-7500 1625);
DISPLAY 1.021277 (-7500 1625);
PAINT ORANGE (-7500 1625);
DISPLAY INVISIBLE (-7500 1625);
FORCEPROP 1 LAST PATH I109
J 0
(-7500 1575);
DISPLAY 0.872340 (-7500 1575);
PAINT PINK (-7500 1575);
DISPLAY INVISIBLE (-7500 1575);
FORCEPROP 2 LAST CDS_LOCATION Y9E1
J 1
(-7520 1574);
DISPLAY 0.617021 (-7520 1574);
PAINT AQUA (-7520 1574);
DISPLAY INVISIBLE (-7520 1574);
FORCEPROP 2 LAST SEC 1
J 0
(-7500 1625);
DISPLAY 0.680851 (-7500 1625);
PAINT MONO (-7500 1625);
DISPLAY INVISIBLE (-7500 1625);
FORCEPROP 2 LAST SEC_TYPE 2013
J 0
(-7500 1625);
DISPLAY 1.021277 (-7500 1625);
PAINT ORANGE (-7500 1625);
DISPLAY INVISIBLE (-7500 1625);
FORCEPROP 2 LAST BOM_COST NT_GBE_BASE
J 0
(-7500 1675);
DISPLAY 1.021277 (-7500 1675);
PAINT ORANGE (-7500 1675);
DISPLAY INVISIBLE (-7500 1675);
FORCEADD RES..1
(-6800 1675);
FORCEPROP 1 LASTPIN (-6900 1675) $PN 1
J 0
(-6888 1687);
DISPLAY 0.617021 (-6888 1687);
PAINT ORANGE (-6888 1687);
FORCEPROP 1 LAST WATTAGE 1/16W
J 0
(-6650 1775);
DISPLAY 0.638298 (-6650 1775);
PAINT SKYBLUE (-6650 1775);
FORCEPROP 1 LAST PACK_TYPE 0402
J 0
(-6625 1725);
DISPLAY 0.638298 (-6625 1725);
PAINT SKYBLUE (-6625 1725);
FORCEPROP 1 LAST TOLERANCE 5%
J 0
(-6750 1775);
DISPLAY 0.617021 (-6750 1775);
PAINT SKYBLUE (-6750 1775);
FORCEPROP 1 LAST LOCATION R9E20
J 0
(-7050 1775);
DISPLAY 0.617021 (-7050 1775);
PAINT AQUA (-7050 1775);
FORCEPROP 1 LAST MATERIAL CHIP
J 0
(-7050 1725);
DISPLAY 0.617021 (-7050 1725);
PAINT SKYBLUE (-7050 1725);
FORCEPROP 1 LASTPIN (-6700 1675) $PN 2
J 0
(-6738 1687);
DISPLAY 0.617021 (-6738 1687);
PAINT ORANGE (-6738 1687);
FORCEPROP 1 LAST PART_NUMBER G21497-005
J 0
(-6900 1725);
DISPLAY 0.638298 (-6900 1725);
PAINT BLUE (-6900 1725);
FORCEPROP 1 LAST VALUE 0.0
J 2
(-6800 1775);
DISPLAY 0.617021 (-6800 1775);
PAINT SKYBLUE (-6800 1775);
FORCEPROP 0 LAST GROUP NI_I210&RJ45
J 0
(-7044 1813);
DISPLAY 0.638298 (-7044 1813);
PAINT BROWN (-7044 1813);
DISPLAY BOTH (-7044 1813);
FORCEPROP 2 LAST CDS_LOCATION R9E20
J 0
(-6850 1725);
DISPLAY 0.617021 (-6850 1725);
PAINT AQUA (-6850 1725);
DISPLAY INVISIBLE (-6850 1725);
FORCEPROP 2 LAST ROOM NIC_SPRV
J 0
(-6850 1775);
DISPLAY 1.021277 (-6850 1775);
PAINT ORANGE (-6850 1775);
DISPLAY INVISIBLE (-6850 1775);
FORCEPROP 2 LAST BOM_COST NT_GBE_BASE
J 0
(-6850 1825);
DISPLAY 1.021277 (-6850 1825);
PAINT ORANGE (-6850 1825);
DISPLAY INVISIBLE (-6850 1825);
FORCEPROP 2 LAST SEC_TYPE 0402
J 0
(-6850 1875);
DISPLAY 1.021277 (-6850 1875);
PAINT ORANGE (-6850 1875);
DISPLAY INVISIBLE (-6850 1875);
FORCEPROP 2 LAST SEC 1
J 0
(-6850 1875);
PAINT MONO (-6850 1875);
DISPLAY INVISIBLE (-6850 1875);
FORCEPROP 1 LAST PATH I110
J 0
(-6850 1825);
DISPLAY 0.978723 (-6850 1825);
PAINT WHITE (-6850 1825);
DISPLAY INVISIBLE (-6850 1825);
FORCEPROP 2 LAST CDS_LIB mstr_discrete
J 0
(-6800 1675);
PAINT ORANGE (-6800 1675);
DISPLAY INVISIBLE (-6800 1675);
FORCEADD GND..1
(-7325 825);
FORCEPROP 3 LASTPIN (-7325 875) SIG_NAME GND\g
J 0
(-7315 885);
DISPLAY 0.659574 (-7315 885);
PAINT MONO (-7315 885);
DISPLAY INVISIBLE (-7315 885);
FORCEPROP 1 LAST VOLTAGE 0.0V
J 0
(-7370 782);
DISPLAY 0.340426 (-7370 782);
PAINT SKYBLUE (-7370 782);
DISPLAY INVISIBLE (-7370 782);
FORCEPROP 1 LAST SIZE 1B
J 0
(-7250 775);
DISPLAY 0.872340 (-7250 775);
PAINT AQUA (-7250 775);
DISPLAY INVISIBLE (-7250 775);
FORCEPROP 2 LAST CDS_LIB mstr_symbols
J 0
(-7325 825);
PAINT ORANGE (-7325 825);
DISPLAY INVISIBLE (-7325 825);
FORCEPROP 1 LAST PATH I113
J 0
(-7250 825);
DISPLAY 0.872340 (-7250 825);
PAINT AQUA (-7250 825);
DISPLAY INVISIBLE (-7250 825);
FORCEPROP 1 LAST BODY_TYPE PLUMBING
J 0
(-7370 782);
DISPLAY 0.340426 (-7370 782);
PAINT GREEN (-7370 782);
DISPLAY INVISIBLE (-7370 782);
FORCEPROP 1 LAST HDL_POWER GND
J 0
(-7325 975);
DISPLAY 0.872340 (-7325 975);
PAINT GREEN (-7325 975);
DISPLAY INVISIBLE (-7325 975);
FORCEADD GND..1
(-7750 825);
FORCEPROP 3 LASTPIN (-7750 875) SIG_NAME GND\g
J 0
(-7740 885);
DISPLAY 0.659574 (-7740 885);
PAINT MONO (-7740 885);
DISPLAY INVISIBLE (-7740 885);
FORCEPROP 2 LAST CDS_LIB mstr_symbols
J 0
(-7750 825);
PAINT ORANGE (-7750 825);
DISPLAY INVISIBLE (-7750 825);
FORCEPROP 1 LAST VOLTAGE 0.0V
J 0
(-7795 782);
DISPLAY 0.340426 (-7795 782);
PAINT SKYBLUE (-7795 782);
DISPLAY INVISIBLE (-7795 782);
FORCEPROP 1 LAST PATH I114
J 0
(-7675 825);
DISPLAY 0.872340 (-7675 825);
PAINT AQUA (-7675 825);
DISPLAY INVISIBLE (-7675 825);
FORCEPROP 1 LAST SIZE 1B
J 0
(-7675 775);
DISPLAY 0.872340 (-7675 775);
PAINT AQUA (-7675 775);
DISPLAY INVISIBLE (-7675 775);
FORCEPROP 1 LAST BODY_TYPE PLUMBING
J 0
(-7795 782);
DISPLAY 0.340426 (-7795 782);
PAINT GREEN (-7795 782);
DISPLAY INVISIBLE (-7795 782);
FORCEPROP 1 LAST HDL_POWER GND
J 0
(-7750 975);
DISPLAY 0.872340 (-7750 975);
PAINT GREEN (-7750 975);
DISPLAY INVISIBLE (-7750 975);
FORCEADD OFFPAGE..2
(-6275 1675);
FORCEPROP 2 LAST $XR0 139 
J 0
(-6086 1675);
DISPLAY 0.638298 (-6086 1675);
PAINT MONO (-6086 1675);
FORCEPROP 2 LAST CDS_LIB mstr_standard
J 0
(-6275 1675);
PAINT ORANGE (-6275 1675);
DISPLAY INVISIBLE (-6275 1675);
FORCEPROP 2 LAST PATH I115
J 0
(-6225 1750);
DISPLAY 1.021277 (-6225 1750);
PAINT ORANGE (-6225 1750);
DISPLAY INVISIBLE (-6225 1750);
FORCEPROP 1 LAST OFFPAGE TRUE
J 0
(-5950 1550);
DISPLAY 0.872340 (-5950 1550);
PAINT GREEN (-5950 1550);
DISPLAY INVISIBLE (-5950 1550);
FORCEPROP 1 LAST COMMENT_BODY TRUE
J 0
(-6320 1580);
DISPLAY 0.872340 (-6320 1580);
PAINT GREEN (-6320 1580);
DISPLAY INVISIBLE (-6320 1580);
FORCEADD OFFPAGE..4
(-6275 1575);
FORCEPROP 2 LAST $XR0 139 
J 0
(-6089 1575);
DISPLAY 0.638298 (-6089 1575);
PAINT MONO (-6089 1575);
FORCEPROP 2 LAST CDS_LIB mstr_standard
J 0
(-6275 1575);
PAINT ORANGE (-6275 1575);
DISPLAY INVISIBLE (-6275 1575);
FORCEPROP 2 LAST PATH I116
J 0
(-6225 1650);
DISPLAY 1.021277 (-6225 1650);
PAINT ORANGE (-6225 1650);
DISPLAY INVISIBLE (-6225 1650);
FORCEPROP 1 LAST OFFPAGE TRUE
J 0
(-5950 1450);
DISPLAY 0.872340 (-5950 1450);
PAINT GREEN (-5950 1450);
DISPLAY INVISIBLE (-5950 1450);
FORCEPROP 1 LAST COMMENT_BODY TRUE
J 0
(-6300 1475);
DISPLAY 0.872340 (-6300 1475);
PAINT GREEN (-6300 1475);
DISPLAY INVISIBLE (-6300 1475);
FORCEADD OFFPAGE..1
(-6050 3375);
FORCEPROP 2 LAST $XR0 139 
J 0
(-6302 3375);
DISPLAY 0.638298 (-6302 3375);
PAINT MONO (-6302 3375);
FORCEPROP 2 LAST CDS_LIB mstr_standard
J 0
(-6050 3375);
PAINT ORANGE (-6050 3375);
DISPLAY INVISIBLE (-6050 3375);
FORCEPROP 2 LAST PATH I117
J 0
(-6000 3450);
DISPLAY 1.021277 (-6000 3450);
PAINT ORANGE (-6000 3450);
DISPLAY INVISIBLE (-6000 3450);
FORCEPROP 1 LAST OFFPAGE TRUE
J 0
(-5725 3250);
DISPLAY 0.872340 (-5725 3250);
PAINT GREEN (-5725 3250);
DISPLAY INVISIBLE (-5725 3250);
FORCEPROP 1 LAST COMMENT_BODY TRUE
J 0
(-5925 3275);
DISPLAY 0.872340 (-5925 3275);
PAINT GREEN (-5925 3275);
DISPLAY INVISIBLE (-5925 3275);
FORCEADD OFFPAGE..5
(-6050 3225);
FORCEPROP 2 LAST $XR0 139 
J 0
(-6305 3225);
DISPLAY 0.638298 (-6305 3225);
PAINT MONO (-6305 3225);
FORCEPROP 2 LAST CDS_LIB mstr_standard
J 0
(-6050 3225);
PAINT ORANGE (-6050 3225);
DISPLAY INVISIBLE (-6050 3225);
FORCEPROP 2 LAST PATH I118
J 0
(-6000 3300);
DISPLAY 1.021277 (-6000 3300);
PAINT ORANGE (-6000 3300);
DISPLAY INVISIBLE (-6000 3300);
FORCEPROP 1 LAST OFFPAGE TRUE
J 0
(-5725 3100);
DISPLAY 0.872340 (-5725 3100);
PAINT GREEN (-5725 3100);
DISPLAY INVISIBLE (-5725 3100);
FORCEPROP 1 LAST COMMENT_BODY TRUE
J 0
(-5950 3150);
DISPLAY 0.872340 (-5950 3150);
PAINT GREEN (-5950 3150);
DISPLAY INVISIBLE (-5950 3150);
FORCEADD OFFPAGE..1
(-6900 2375);
FORCEPROP 2 LAST $XR0 140 
J 0
(-7152 2375);
DISPLAY 0.638298 (-7152 2375);
PAINT MONO (-7152 2375);
FORCEPROP 1 LAST COMMENT_BODY TRUE
J 0
(-6775 2275);
DISPLAY 0.872340 (-6775 2275);
PAINT GREEN (-6775 2275);
DISPLAY INVISIBLE (-6775 2275);
FORCEPROP 1 LAST OFFPAGE TRUE
J 0
(-6575 2250);
DISPLAY 0.872340 (-6575 2250);
PAINT GREEN (-6575 2250);
DISPLAY INVISIBLE (-6575 2250);
FORCEPROP 2 LAST PATH I127
J 0
(-6850 2450);
DISPLAY 1.021277 (-6850 2450);
PAINT ORANGE (-6850 2450);
DISPLAY INVISIBLE (-6850 2450);
FORCEPROP 2 LAST CDS_LIB mstr_standard
J 0
(-6900 2375);
PAINT ORANGE (-6900 2375);
DISPLAY INVISIBLE (-6900 2375);
FORCEADD RES..1
(-2400 2375);
FORCEPROP 1 LAST PACK_TYPE 0402
J 0
(-2275 2375);
DISPLAY 0.617021 (-2275 2375);
PAINT SKYBLUE (-2275 2375);
FORCEPROP 1 LAST VALUE 33.2
J 2
(-2550 2425);
DISPLAY 0.617021 (-2550 2425);
PAINT SKYBLUE (-2550 2425);
FORCEPROP 1 LAST MATERIAL CHIP
J 0
(-2225 2425);
DISPLAY 0.617021 (-2225 2425);
PAINT SKYBLUE (-2225 2425);
FORCEPROP 1 LASTPIN (-2500 2375) $PN 1
J 0
(-2488 2387);
DISPLAY 0.617021 (-2488 2387);
PAINT ORANGE (-2488 2387);
FORCEPROP 1 LAST LOCATION R9E9
J 0
(-2825 2425);
DISPLAY 0.617021 (-2825 2425);
PAINT AQUA (-2825 2425);
FORCEPROP 1 LAST TOLERANCE 1%
J 0
(-2500 2425);
DISPLAY 0.617021 (-2500 2425);
PAINT SKYBLUE (-2500 2425);
FORCEPROP 1 LASTPIN (-2300 2375) $PN 2
J 0
(-2338 2387);
DISPLAY 0.617021 (-2338 2387);
PAINT ORANGE (-2338 2387);
FORCEPROP 1 LAST PART_NUMBER G21796-074
J 0
(-2700 2375);
DISPLAY 0.617021 (-2700 2375);
PAINT BLUE (-2700 2375);
FORCEPROP 0 LAST GROUP NI_I210&RJ45
J 0
(-2494 2338);
DISPLAY 0.638298 (-2494 2338);
PAINT BROWN (-2494 2338);
DISPLAY BOTH (-2494 2338);
FORCEPROP 1 LAST WATTAGE 1/16W
J 2
(-2275 2425);
DISPLAY 0.617021 (-2275 2425);
PAINT SKYBLUE (-2275 2425);
FORCEPROP 2 LAST SEC_TYPE 0402
J 0
(-2450 2575);
DISPLAY 1.021277 (-2450 2575);
PAINT ORANGE (-2450 2575);
DISPLAY INVISIBLE (-2450 2575);
FORCEPROP 2 LAST SEC 1
J 0
(-2450 2575);
PAINT MONO (-2450 2575);
DISPLAY INVISIBLE (-2450 2575);
FORCEPROP 2 LAST BOM_COST NT_GBE_BASE
J 0
(-2475 2525);
DISPLAY 1.021277 (-2475 2525);
PAINT ORANGE (-2475 2525);
DISPLAY INVISIBLE (-2475 2525);
FORCEPROP 1 LAST PATH I128
J 0
(-2450 2525);
DISPLAY 0.978723 (-2450 2525);
PAINT WHITE (-2450 2525);
DISPLAY INVISIBLE (-2450 2525);
FORCEPROP 2 LAST CDS_LOCATION R9E9
J 0
(-2250 2375);
DISPLAY 0.617021 (-2250 2375);
PAINT AQUA (-2250 2375);
DISPLAY INVISIBLE (-2250 2375);
FORCEPROP 2 LAST CDS_LIB mstr_discrete
J 0
(-2400 2375);
PAINT ORANGE (-2400 2375);
DISPLAY INVISIBLE (-2400 2375);
FORCEPROP 2 LAST ROOM NIC_SPRV
J 0
(-2475 2475);
DISPLAY 1.021277 (-2475 2475);
PAINT ORANGE (-2475 2475);
DISPLAY INVISIBLE (-2475 2475);
FORCEADD RES..1
(-1850 2325);
FORCEPROP 1 LAST WATTAGE 1/16W
J 0
(-1575 2275);
DISPLAY 0.617021 (-1575 2275);
PAINT SKYBLUE (-1575 2275);
FORCEPROP 1 LAST MATERIAL CHIP
J 0
(-2025 2225);
DISPLAY 0.617021 (-2025 2225);
PAINT SKYBLUE (-2025 2225);
FORCEPROP 0 LAST SEC_TYPE 0402
J 0
(-1575 2225);
DISPLAY 0.638298 (-1575 2225);
PAINT SKYBLUE (-1575 2225);
FORCEPROP 1 LAST TOLERANCE 1%
J 0
(-1725 2275);
DISPLAY 0.617021 (-1725 2275);
PAINT SKYBLUE (-1725 2275);
FORCEPROP 1 LASTPIN (-1750 2325) $PN 2
J 0
(-1788 2337);
DISPLAY 0.617021 (-1788 2337);
PAINT ORANGE (-1788 2337);
FORCEPROP 1 LAST VALUE 33.2
J 0
(-1875 2275);
DISPLAY 0.617021 (-1875 2275);
PAINT SKYBLUE (-1875 2275);
FORCEPROP 0 LAST GROUP NI_I210&RJ45
J 0
(-1944 2188);
DISPLAY 0.638298 (-1944 2188);
PAINT BROWN (-1944 2188);
DISPLAY BOTH (-1944 2188);
FORCEPROP 1 LAST LOCATION R9E5
J 0
(-2025 2275);
DISPLAY 0.617021 (-2025 2275);
PAINT AQUA (-2025 2275);
FORCEPROP 1 LASTPIN (-1950 2325) $PN 1
J 0
(-1938 2337);
DISPLAY 0.617021 (-1938 2337);
PAINT ORANGE (-1938 2337);
FORCEPROP 1 LAST PART_NUMBER G21796-074
J 0
(-1850 2225);
DISPLAY 0.617021 (-1850 2225);
PAINT BLUE (-1850 2225);
FORCEPROP 2 LAST CDS_LOCATION R9E5
J 0
(-1750 2325);
DISPLAY 0.617021 (-1750 2325);
PAINT AQUA (-1750 2325);
DISPLAY INVISIBLE (-1750 2325);
FORCEPROP 1 LAST PACK_TYPE 0402
J 0
(-1750 2325);
DISPLAY 0.617021 (-1750 2325);
PAINT SKYBLUE (-1750 2325);
DISPLAY INVISIBLE (-1750 2325);
FORCEPROP 2 LAST BOM_COST NT_GBE_BASE
J 0
(-2100 2525);
DISPLAY 1.021277 (-2100 2525);
PAINT ORANGE (-2100 2525);
DISPLAY INVISIBLE (-2100 2525);
FORCEPROP 2 LAST SEC 1
J 0
(-1900 2525);
PAINT MONO (-1900 2525);
DISPLAY INVISIBLE (-1900 2525);
FORCEPROP 2 LAST CDS_LIB mstr_discrete
J 0
(-1850 2325);
PAINT ORANGE (-1850 2325);
DISPLAY INVISIBLE (-1850 2325);
FORCEPROP 1 LAST PATH I129
J 0
(-1900 2475);
DISPLAY 0.978723 (-1900 2475);
PAINT WHITE (-1900 2475);
DISPLAY INVISIBLE (-1900 2475);
FORCEPROP 2 LAST ROOM NIC_SPRV
J 0
(-2100 2475);
DISPLAY 1.021277 (-2100 2475);
PAINT ORANGE (-2100 2475);
DISPLAY INVISIBLE (-2100 2475);
FORCEADD RES..1
(-2400 2275);
FORCEPROP 1 LAST PACK_TYPE 0402
J 0
(-2250 2275);
DISPLAY 0.617021 (-2250 2275);
PAINT SKYBLUE (-2250 2275);
FORCEPROP 1 LAST WATTAGE 1/16W
J 2
(-2500 2225);
DISPLAY 0.617021 (-2500 2225);
PAINT SKYBLUE (-2500 2225);
FORCEPROP 1 LAST MATERIAL CHIP
J 0
(-2450 2225);
DISPLAY 0.617021 (-2450 2225);
PAINT SKYBLUE (-2450 2225);
FORCEPROP 1 LASTPIN (-2300 2275) $PN 2
J 0
(-2338 2287);
DISPLAY 0.617021 (-2338 2287);
PAINT ORANGE (-2338 2287);
FORCEPROP 1 LAST TOLERANCE 1%
J 0
(-2750 2225);
DISPLAY 0.617021 (-2750 2225);
PAINT SKYBLUE (-2750 2225);
FORCEPROP 1 LAST VALUE 33.2
J 2
(-2800 2225);
DISPLAY 0.617021 (-2800 2225);
PAINT SKYBLUE (-2800 2225);
FORCEPROP 1 LAST LOCATION R9E8
J 0
(-3050 2225);
DISPLAY 0.617021 (-3050 2225);
PAINT AQUA (-3050 2225);
FORCEPROP 1 LASTPIN (-2500 2275) $PN 1
J 0
(-2488 2287);
DISPLAY 0.617021 (-2488 2287);
PAINT ORANGE (-2488 2287);
FORCEPROP 0 LAST GROUP NI_I210&RJ45
J 0
(-2444 2188);
DISPLAY 0.638298 (-2444 2188);
PAINT BROWN (-2444 2188);
DISPLAY BOTH (-2444 2188);
FORCEPROP 1 LAST PART_NUMBER G21796-074
J 0
(-2325 2225);
DISPLAY 0.617021 (-2325 2225);
PAINT BLUE (-2325 2225);
FORCEPROP 2 LAST CDS_LOCATION R9E8
J 0
(-2275 2275);
DISPLAY 0.617021 (-2275 2275);
PAINT AQUA (-2275 2275);
DISPLAY INVISIBLE (-2275 2275);
FORCEPROP 2 LAST BOM_COST NT_GBE_BASE
J 0
(-2425 2400);
DISPLAY 1.021277 (-2425 2400);
PAINT ORANGE (-2425 2400);
DISPLAY INVISIBLE (-2425 2400);
FORCEPROP 2 LAST ROOM NIC_SPRV
J 0
(-2425 2350);
DISPLAY 1.021277 (-2425 2350);
PAINT ORANGE (-2425 2350);
DISPLAY INVISIBLE (-2425 2350);
FORCEPROP 2 LAST SEC_TYPE 0402
J 0
(-2450 2475);
DISPLAY 1.021277 (-2450 2475);
PAINT ORANGE (-2450 2475);
DISPLAY INVISIBLE (-2450 2475);
FORCEPROP 2 LAST SEC 1
J 0
(-2450 2475);
PAINT MONO (-2450 2475);
DISPLAY INVISIBLE (-2450 2475);
FORCEPROP 1 LAST PATH I130
J 0
(-2450 2425);
DISPLAY 0.978723 (-2450 2425);
PAINT WHITE (-2450 2425);
DISPLAY INVISIBLE (-2450 2425);
FORCEPROP 2 LAST CDS_LIB mstr_discrete
J 0
(-2400 2275);
PAINT ORANGE (-2400 2275);
DISPLAY INVISIBLE (-2400 2275);
FORCEADD OFFPAGE..2
(-700 2375);
FORCEPROP 2 LAST $XR0 140 
J 0
(-511 2375);
DISPLAY 0.638298 (-511 2375);
PAINT MONO (-511 2375);
FORCEPROP 1 LAST COMMENT_BODY TRUE
J 0
(-745 2280);
DISPLAY 0.872340 (-745 2280);
PAINT GREEN (-745 2280);
DISPLAY INVISIBLE (-745 2280);
FORCEPROP 1 LAST OFFPAGE TRUE
J 0
(-375 2250);
DISPLAY 0.872340 (-375 2250);
PAINT GREEN (-375 2250);
DISPLAY INVISIBLE (-375 2250);
FORCEPROP 2 LAST PATH I131
J 0
(-650 2450);
DISPLAY 1.021277 (-650 2450);
PAINT ORANGE (-650 2450);
DISPLAY INVISIBLE (-650 2450);
FORCEPROP 2 LAST CDS_LIB mstr_standard
J 0
(-700 2375);
PAINT ORANGE (-700 2375);
DISPLAY INVISIBLE (-700 2375);
FORCEADD OFFPAGE..2
(-700 2325);
FORCEPROP 2 LAST $XR0 140 
J 0
(-511 2325);
DISPLAY 0.638298 (-511 2325);
PAINT MONO (-511 2325);
FORCEPROP 1 LAST COMMENT_BODY TRUE
J 0
(-745 2230);
DISPLAY 0.872340 (-745 2230);
PAINT GREEN (-745 2230);
DISPLAY INVISIBLE (-745 2230);
FORCEPROP 1 LAST OFFPAGE TRUE
J 0
(-375 2200);
DISPLAY 0.872340 (-375 2200);
PAINT GREEN (-375 2200);
DISPLAY INVISIBLE (-375 2200);
FORCEPROP 2 LAST PATH I132
J 0
(-650 2400);
DISPLAY 1.021277 (-650 2400);
PAINT ORANGE (-650 2400);
DISPLAY INVISIBLE (-650 2400);
FORCEPROP 2 LAST CDS_LIB mstr_standard
J 0
(-700 2325);
PAINT ORANGE (-700 2325);
DISPLAY INVISIBLE (-700 2325);
FORCEADD OFFPAGE..2
(-700 2275);
FORCEPROP 2 LAST $XR0 140 
J 0
(-511 2275);
DISPLAY 0.638298 (-511 2275);
PAINT MONO (-511 2275);
FORCEPROP 1 LAST COMMENT_BODY TRUE
J 0
(-745 2180);
DISPLAY 0.872340 (-745 2180);
PAINT GREEN (-745 2180);
DISPLAY INVISIBLE (-745 2180);
FORCEPROP 1 LAST OFFPAGE TRUE
J 0
(-375 2150);
DISPLAY 0.872340 (-375 2150);
PAINT GREEN (-375 2150);
DISPLAY INVISIBLE (-375 2150);
FORCEPROP 2 LAST PATH I133
J 0
(-525 2350);
DISPLAY 1.021277 (-525 2350);
PAINT ORANGE (-525 2350);
DISPLAY INVISIBLE (-525 2350);
FORCEPROP 2 LAST CDS_LIB mstr_standard
J 0
(-700 2275);
PAINT ORANGE (-700 2275);
DISPLAY INVISIBLE (-700 2275);
FORCEADD CAP..1
(-5975 4275);
FORCEPROP 0 LAST GROUP NI_I210&RJ45
J 0
(-5919 4038);
DISPLAY 0.638298 (-5919 4038);
PAINT BROWN (-5919 4038);
DISPLAY BOTH (-5919 4038);
FORCEPROP 1 LASTPIN (-5975 4175) $PN 2
J 0
(-5965 4155);
DISPLAY 0.617021 (-5965 4155);
PAINT ORANGE (-5965 4155);
FORCEPROP 1 LAST MATERIAL X6S
J 0
(-5925 4175);
DISPLAY 0.617021 (-5925 4175);
PAINT SKYBLUE (-5925 4175);
FORCEPROP 1 LASTPIN (-5975 4375) $PN 1
J 0
(-5965 4355);
DISPLAY 0.617021 (-5965 4355);
PAINT ORANGE (-5965 4355);
FORCEPROP 1 LAST PACK_TYPE 0603
J 0
(-5925 4075);
DISPLAY 0.617021 (-5925 4075);
PAINT SKYBLUE (-5925 4075);
FORCEPROP 1 LAST PART_NUMBER E15431-002
J 0
(-5925 4125);
DISPLAY 0.617021 (-5925 4125);
PAINT BLUE (-5925 4125);
FORCEPROP 1 LAST TOLERANCE 20%
J 0
(-5925 4225);
DISPLAY 0.617021 (-5925 4225);
PAINT SKYBLUE (-5925 4225);
FORCEPROP 1 LAST VOLTAGE 6.3V
J 0
(-5925 4275);
DISPLAY 0.617021 (-5925 4275);
PAINT SKYBLUE (-5925 4275);
FORCEPROP 1 LAST VALUE 10UF
J 0
(-5925 4325);
DISPLAY 0.617021 (-5925 4325);
PAINT SKYBLUE (-5925 4325);
FORCEPROP 1 LAST LOCATION C1T4
J 0
(-5925 4375);
DISPLAY 0.617021 (-5925 4375);
PAINT AQUA (-5925 4375);
FORCEPROP 2 LAST CDS_LIB mstr_discrete
J 0
(-5975 4275);
PAINT ORANGE (-5975 4275);
DISPLAY INVISIBLE (-5975 4275);
FORCEPROP 1 LAST PATH I134
J 0
(-5925 4425);
DISPLAY 0.978723 (-5925 4425);
PAINT WHITE (-5925 4425);
DISPLAY INVISIBLE (-5925 4425);
FORCEPROP 2 LAST BOM_COST NT_GBE_BASE
J 0
(-5925 4475);
DISPLAY 1.021277 (-5925 4475);
PAINT ORANGE (-5925 4475);
DISPLAY INVISIBLE (-5925 4475);
FORCEPROP 2 LAST ROOM NIC_SPRV
J 0
(-5925 4425);
DISPLAY 1.021277 (-5925 4425);
PAINT ORANGE (-5925 4425);
DISPLAY INVISIBLE (-5925 4425);
FORCEPROP 2 LAST SEC_TYPE 0603
J 0
(-5925 4475);
DISPLAY 1.021277 (-5925 4475);
PAINT ORANGE (-5925 4475);
DISPLAY INVISIBLE (-5925 4475);
FORCEPROP 2 LAST SEC 1
J 0
(-5925 4475);
PAINT MONO (-5925 4475);
DISPLAY INVISIBLE (-5925 4475);
FORCEPROP 2 LAST CDS_LOCATION C1T4
J 0
(-5925 4375);
DISPLAY 0.617021 (-5925 4375);
PAINT AQUA (-5925 4375);
DISPLAY INVISIBLE (-5925 4375);
FORCEADD CAP..1
(-6375 3975);
FORCEPROP 0 LAST GROUP NI_I210&RJ45
J 0
(-6319 3738);
DISPLAY 0.638298 (-6319 3738);
PAINT BROWN (-6319 3738);
DISPLAY BOTH (-6319 3738);
FORCEPROP 1 LAST LOCATION C1R30
J 0
(-6325 4075);
DISPLAY 0.617021 (-6325 4075);
PAINT AQUA (-6325 4075);
FORCEPROP 1 LAST VALUE 10UF
J 0
(-6325 4025);
DISPLAY 0.617021 (-6325 4025);
PAINT SKYBLUE (-6325 4025);
FORCEPROP 1 LAST PACK_TYPE 0603
J 0
(-6325 3775);
DISPLAY 0.617021 (-6325 3775);
PAINT SKYBLUE (-6325 3775);
FORCEPROP 1 LAST MATERIAL X6S
J 0
(-6325 3875);
DISPLAY 0.617021 (-6325 3875);
PAINT SKYBLUE (-6325 3875);
FORCEPROP 1 LASTPIN (-6375 4075) $PN 1
J 0
(-6365 4055);
DISPLAY 0.617021 (-6365 4055);
PAINT ORANGE (-6365 4055);
FORCEPROP 1 LAST TOLERANCE 20%
J 0
(-6325 3925);
DISPLAY 0.617021 (-6325 3925);
PAINT SKYBLUE (-6325 3925);
FORCEPROP 1 LASTPIN (-6375 3875) $PN 2
J 0
(-6365 3855);
DISPLAY 0.617021 (-6365 3855);
PAINT ORANGE (-6365 3855);
FORCEPROP 1 LAST VOLTAGE 6.3V
J 0
(-6325 3975);
DISPLAY 0.617021 (-6325 3975);
PAINT SKYBLUE (-6325 3975);
FORCEPROP 1 LAST PART_NUMBER E15431-002
J 0
(-6325 3825);
DISPLAY 0.617021 (-6325 3825);
PAINT BLUE (-6325 3825);
FORCEPROP 2 LAST ROOM NIC_SPRV
J 0
(-6325 4125);
DISPLAY 1.021277 (-6325 4125);
PAINT ORANGE (-6325 4125);
DISPLAY INVISIBLE (-6325 4125);
FORCEPROP 1 LAST PATH I135
J 0
(-6325 4125);
DISPLAY 0.978723 (-6325 4125);
PAINT WHITE (-6325 4125);
DISPLAY INVISIBLE (-6325 4125);
FORCEPROP 2 LAST SEC 1
J 0
(-6325 4175);
PAINT MONO (-6325 4175);
DISPLAY INVISIBLE (-6325 4175);
FORCEPROP 2 LAST BOM_COST NT_GBE_BASE
J 0
(-6325 4175);
DISPLAY 1.021277 (-6325 4175);
PAINT ORANGE (-6325 4175);
DISPLAY INVISIBLE (-6325 4175);
FORCEPROP 2 LAST SEC_TYPE 0603
J 0
(-6325 4175);
DISPLAY 1.021277 (-6325 4175);
PAINT ORANGE (-6325 4175);
DISPLAY INVISIBLE (-6325 4175);
FORCEPROP 2 LAST CDS_LOCATION C1R30
J 0
(-6325 4075);
DISPLAY 0.617021 (-6325 4075);
PAINT AQUA (-6325 4075);
DISPLAY INVISIBLE (-6325 4075);
FORCEPROP 2 LAST CDS_LIB mstr_discrete
J 0
(-6375 3975);
PAINT ORANGE (-6375 3975);
DISPLAY INVISIBLE (-6375 3975);
FORCEADD CAP..1
(-6950 3750);
FORCEPROP 0 LAST GROUP NI_I210&RJ45
J 0
(-6894 3488);
DISPLAY 0.638298 (-6894 3488);
PAINT BROWN (-6894 3488);
DISPLAY BOTH (-6894 3488);
FORCEPROP 1 LAST PART_NUMBER E15431-002
J 0
(-6900 3600);
DISPLAY 0.617021 (-6900 3600);
PAINT BLUE (-6900 3600);
FORCEPROP 1 LAST VOLTAGE 6.3V
J 0
(-6900 3750);
DISPLAY 0.617021 (-6900 3750);
PAINT SKYBLUE (-6900 3750);
FORCEPROP 1 LAST VALUE 10UF
J 0
(-6900 3800);
DISPLAY 0.617021 (-6900 3800);
PAINT SKYBLUE (-6900 3800);
FORCEPROP 1 LAST MATERIAL X6S
J 0
(-6900 3650);
DISPLAY 0.617021 (-6900 3650);
PAINT SKYBLUE (-6900 3650);
FORCEPROP 1 LASTPIN (-6950 3850) $PN 1
J 0
(-6940 3830);
DISPLAY 0.617021 (-6940 3830);
PAINT ORANGE (-6940 3830);
FORCEPROP 1 LASTPIN (-6950 3650) $PN 2
J 0
(-6940 3630);
DISPLAY 0.617021 (-6940 3630);
PAINT ORANGE (-6940 3630);
FORCEPROP 1 LAST LOCATION C1R22
J 0
(-6900 3850);
DISPLAY 0.617021 (-6900 3850);
PAINT AQUA (-6900 3850);
FORCEPROP 1 LAST TOLERANCE 20%
J 0
(-6900 3700);
DISPLAY 0.617021 (-6900 3700);
PAINT SKYBLUE (-6900 3700);
FORCEPROP 1 LAST PACK_TYPE 0603
J 0
(-6900 3550);
DISPLAY 0.617021 (-6900 3550);
PAINT SKYBLUE (-6900 3550);
FORCEPROP 2 LAST CDS_LIB mstr_discrete
J 0
(-6950 3750);
PAINT ORANGE (-6950 3750);
DISPLAY INVISIBLE (-6950 3750);
FORCEPROP 2 LAST CDS_LOCATION C1R22
J 0
(-6900 3850);
DISPLAY 0.617021 (-6900 3850);
PAINT AQUA (-6900 3850);
DISPLAY INVISIBLE (-6900 3850);
FORCEPROP 1 LAST PATH I136
J 0
(-6900 3900);
DISPLAY 0.978723 (-6900 3900);
PAINT WHITE (-6900 3900);
DISPLAY INVISIBLE (-6900 3900);
FORCEPROP 2 LAST ROOM NIC_SPRV
J 0
(-6900 3900);
DISPLAY 1.021277 (-6900 3900);
PAINT ORANGE (-6900 3900);
DISPLAY INVISIBLE (-6900 3900);
FORCEPROP 2 LAST SEC 1
J 0
(-6900 3950);
PAINT MONO (-6900 3950);
DISPLAY INVISIBLE (-6900 3950);
FORCEPROP 2 LAST BOM_COST NT_GBE_BASE
J 0
(-6900 3950);
DISPLAY 1.021277 (-6900 3950);
PAINT ORANGE (-6900 3950);
DISPLAY INVISIBLE (-6900 3950);
FORCEPROP 2 LAST SEC_TYPE 0603
J 0
(-6900 3950);
DISPLAY 1.021277 (-6900 3950);
PAINT ORANGE (-6900 3950);
DISPLAY INVISIBLE (-6900 3950);
FORCEADD GND..1
(-6950 3500);
FORCEPROP 3 LASTPIN (-6950 3550) SIG_NAME GND\g
J 0
(-6940 3560);
DISPLAY 0.659574 (-6940 3560);
PAINT MONO (-6940 3560);
DISPLAY INVISIBLE (-6940 3560);
FORCEPROP 2 LAST CDS_LIB mstr_symbols
J 0
(-6950 3500);
PAINT ORANGE (-6950 3500);
DISPLAY INVISIBLE (-6950 3500);
FORCEPROP 1 LAST VOLTAGE 0.0V
J 0
(-6995 3457);
DISPLAY 0.340426 (-6995 3457);
PAINT SKYBLUE (-6995 3457);
DISPLAY INVISIBLE (-6995 3457);
FORCEPROP 1 LAST PATH I137
J 0
(-6875 3500);
DISPLAY 0.872340 (-6875 3500);
PAINT AQUA (-6875 3500);
DISPLAY INVISIBLE (-6875 3500);
FORCEPROP 1 LAST SIZE 1B
J 0
(-6875 3450);
DISPLAY 0.872340 (-6875 3450);
PAINT AQUA (-6875 3450);
DISPLAY INVISIBLE (-6875 3450);
FORCEPROP 1 LAST BODY_TYPE PLUMBING
J 0
(-6995 3457);
DISPLAY 0.340426 (-6995 3457);
PAINT GREEN (-6995 3457);
DISPLAY INVISIBLE (-6995 3457);
FORCEPROP 1 LAST HDL_POWER GND
J 0
(-6950 3650);
DISPLAY 0.872340 (-6950 3650);
PAINT GREEN (-6950 3650);
DISPLAY INVISIBLE (-6950 3650);
FORCEADD GND..1
(-6375 3750);
FORCEPROP 3 LASTPIN (-6375 3800) SIG_NAME GND\g
J 0
(-6365 3810);
DISPLAY 0.659574 (-6365 3810);
PAINT MONO (-6365 3810);
DISPLAY INVISIBLE (-6365 3810);
FORCEPROP 1 LAST HDL_POWER GND
J 0
(-6375 3900);
DISPLAY 0.872340 (-6375 3900);
PAINT GREEN (-6375 3900);
DISPLAY INVISIBLE (-6375 3900);
FORCEPROP 1 LAST BODY_TYPE PLUMBING
J 0
(-6420 3707);
DISPLAY 0.340426 (-6420 3707);
PAINT GREEN (-6420 3707);
DISPLAY INVISIBLE (-6420 3707);
FORCEPROP 1 LAST VOLTAGE 0.0V
J 0
(-6420 3707);
DISPLAY 0.340426 (-6420 3707);
PAINT SKYBLUE (-6420 3707);
DISPLAY INVISIBLE (-6420 3707);
FORCEPROP 2 LAST CDS_LIB mstr_symbols
J 0
(-6375 3750);
PAINT ORANGE (-6375 3750);
DISPLAY INVISIBLE (-6375 3750);
FORCEPROP 1 LAST SIZE 1B
J 0
(-6300 3700);
DISPLAY 0.872340 (-6300 3700);
PAINT AQUA (-6300 3700);
DISPLAY INVISIBLE (-6300 3700);
FORCEPROP 1 LAST PATH I138
J 0
(-6300 3750);
DISPLAY 0.872340 (-6300 3750);
PAINT AQUA (-6300 3750);
DISPLAY INVISIBLE (-6300 3750);
FORCEADD GND..1
(-5975 4050);
FORCEPROP 3 LASTPIN (-5975 4100) SIG_NAME GND\g
J 0
(-5965 4110);
DISPLAY 0.659574 (-5965 4110);
PAINT MONO (-5965 4110);
DISPLAY INVISIBLE (-5965 4110);
FORCEPROP 1 LAST VOLTAGE 0.0V
J 0
(-6020 4007);
DISPLAY 0.340426 (-6020 4007);
PAINT SKYBLUE (-6020 4007);
DISPLAY INVISIBLE (-6020 4007);
FORCEPROP 1 LAST PATH I139
J 0
(-5900 4050);
DISPLAY 0.872340 (-5900 4050);
PAINT AQUA (-5900 4050);
DISPLAY INVISIBLE (-5900 4050);
FORCEPROP 2 LAST CDS_LIB mstr_symbols
J 0
(-5975 4050);
PAINT ORANGE (-5975 4050);
DISPLAY INVISIBLE (-5975 4050);
FORCEPROP 1 LAST SIZE 1B
J 0
(-5900 4000);
DISPLAY 0.872340 (-5900 4000);
PAINT AQUA (-5900 4000);
DISPLAY INVISIBLE (-5900 4000);
FORCEPROP 1 LAST BODY_TYPE PLUMBING
J 0
(-6020 4007);
DISPLAY 0.340426 (-6020 4007);
PAINT GREEN (-6020 4007);
DISPLAY INVISIBLE (-6020 4007);
FORCEPROP 1 LAST HDL_POWER GND
J 0
(-5975 4200);
DISPLAY 0.872340 (-5975 4200);
PAINT GREEN (-5975 4200);
DISPLAY INVISIBLE (-5975 4200);
FORCEADD CAP..1
(-5450 850);
FORCEPROP 1 LAST PACK_TYPE 0603
J 0
(-5400 650);
DISPLAY 0.617021 (-5400 650);
PAINT SKYBLUE (-5400 650);
FORCEPROP 1 LAST VALUE 10UF
J 0
(-5400 900);
DISPLAY 0.617021 (-5400 900);
PAINT SKYBLUE (-5400 900);
FORCEPROP 1 LASTPIN (-5450 750) $PN 2
J 0
(-5440 730);
DISPLAY 0.617021 (-5440 730);
PAINT ORANGE (-5440 730);
FORCEPROP 1 LASTPIN (-5450 950) $PN 1
J 0
(-5440 930);
DISPLAY 0.617021 (-5440 930);
PAINT ORANGE (-5440 930);
FORCEPROP 1 LAST LOCATION C1R13
J 0
(-5400 950);
DISPLAY 0.617021 (-5400 950);
PAINT AQUA (-5400 950);
FORCEPROP 1 LAST PART_NUMBER E15431-002
J 0
(-5400 700);
DISPLAY 0.617021 (-5400 700);
PAINT BLUE (-5400 700);
FORCEPROP 1 LAST MATERIAL X6S
J 0
(-5400 750);
DISPLAY 0.617021 (-5400 750);
PAINT SKYBLUE (-5400 750);
FORCEPROP 1 LAST TOLERANCE 20%
J 0
(-5400 800);
DISPLAY 0.617021 (-5400 800);
PAINT SKYBLUE (-5400 800);
FORCEPROP 1 LAST VOLTAGE 6.3V
J 0
(-5400 850);
DISPLAY 0.617021 (-5400 850);
PAINT SKYBLUE (-5400 850);
FORCEPROP 0 LAST GROUP NI_I210&RJ45
J 0
(-5394 563);
DISPLAY 0.638298 (-5394 563);
PAINT BROWN (-5394 563);
DISPLAY BOTH (-5394 563);
FORCEPROP 2 LAST CDS_LIB mstr_discrete
J 0
(-5450 850);
PAINT ORANGE (-5450 850);
DISPLAY INVISIBLE (-5450 850);
FORCEPROP 2 LAST CDS_LOCATION C1R13
J 0
(-5400 950);
DISPLAY 0.617021 (-5400 950);
PAINT AQUA (-5400 950);
DISPLAY INVISIBLE (-5400 950);
FORCEPROP 2 LAST BOM_COST NT_GBE_BASE
J 0
(-5400 1050);
DISPLAY 1.021277 (-5400 1050);
PAINT ORANGE (-5400 1050);
DISPLAY INVISIBLE (-5400 1050);
FORCEPROP 2 LAST CDS_SEC 1
J 0
(-5400 1050);
PAINT MONO (-5400 1050);
DISPLAY INVISIBLE (-5400 1050);
FORCEPROP 2 LAST ROOM NIC_SPRV
J 0
(-5400 1000);
DISPLAY 1.021277 (-5400 1000);
PAINT ORANGE (-5400 1000);
DISPLAY INVISIBLE (-5400 1000);
FORCEPROP 1 LAST PATH I142
J 0
(-5400 1000);
DISPLAY 0.978723 (-5400 1000);
PAINT WHITE (-5400 1000);
DISPLAY INVISIBLE (-5400 1000);
FORCEPROP 2 LAST $SEC 1
J 0
(-5400 1050);
PAINT MONO (-5400 1050);
DISPLAY INVISIBLE (-5400 1050);
FORCEADD CAP_A..1
(-5200 850);
FORCEPROP 1 LASTPIN (-5200 750) $PN 2
J 0
(-5190 730);
DISPLAY 0.617021 (-5190 730);
PAINT ORANGE (-5190 730);
FORCEPROP 1 LAST TOLERANCE 10%
J 0
(-5150 800);
DISPLAY 0.617021 (-5150 800);
PAINT SKYBLUE (-5150 800);
FORCEPROP 1 LASTPIN (-5200 950) $PN 1
J 0
(-5190 930);
DISPLAY 0.617021 (-5190 930);
PAINT ORANGE (-5190 930);
FORCEPROP 1 LAST LOCATION C1R20
J 0
(-5150 950);
DISPLAY 0.617021 (-5150 950);
PAINT AQUA (-5150 950);
FORCEPROP 1 LAST MATERIAL X7R
J 0
(-5150 750);
DISPLAY 0.617021 (-5150 750);
PAINT SKYBLUE (-5150 750);
FORCEPROP 1 LAST VOLTAGE 16V
J 0
(-5150 850);
DISPLAY 0.617021 (-5150 850);
PAINT SKYBLUE (-5150 850);
FORCEPROP 1 LAST VALUE 0.1UF
J 0
(-5150 900);
DISPLAY 0.617021 (-5150 900);
PAINT SKYBLUE (-5150 900);
FORCEPROP 1 LAST PACK_TYPE 0402V
J 0
(-5150 650);
DISPLAY 0.617021 (-5150 650);
PAINT SKYBLUE (-5150 650);
FORCEPROP 1 LAST PART_NUMBER A36096-030
J 0
(-5150 700);
DISPLAY 0.617021 (-5150 700);
PAINT BLUE (-5150 700);
FORCEPROP 0 LAST GROUP NI_I210&RJ45
J 0
(-5144 513);
DISPLAY 0.638298 (-5144 513);
PAINT BROWN (-5144 513);
DISPLAY BOTH (-5144 513);
FORCEPROP 2 LAST CDS_LOCATION C1R20
J 0
(-5150 950);
DISPLAY 0.617021 (-5150 950);
PAINT AQUA (-5150 950);
DISPLAY INVISIBLE (-5150 950);
FORCEPROP 2 LAST CDS_LIB dev_discrete
J 0
(-5200 850);
PAINT ORANGE (-5200 850);
DISPLAY INVISIBLE (-5200 850);
FORCEPROP 2 LAST $SEC 1
J 0
(-5150 1050);
PAINT MONO (-5150 1050);
DISPLAY INVISIBLE (-5150 1050);
FORCEPROP 2 LAST CDS_SEC 1
J 0
(-5150 1050);
PAINT MONO (-5150 1050);
DISPLAY INVISIBLE (-5150 1050);
FORCEPROP 2 LAST BOM_COST NT_GBE_BASE
J 0
(-5150 1050);
DISPLAY 1.021277 (-5150 1050);
PAINT ORANGE (-5150 1050);
DISPLAY INVISIBLE (-5150 1050);
FORCEPROP 2 LAST ROOM NIC_SPRV
J 0
(-5150 1000);
DISPLAY 1.021277 (-5150 1000);
PAINT ORANGE (-5150 1000);
DISPLAY INVISIBLE (-5150 1000);
FORCEPROP 1 LAST PATH I143
J 0
(-5150 1000);
DISPLAY 0.978723 (-5150 1000);
PAINT WHITE (-5150 1000);
DISPLAY INVISIBLE (-5150 1000);
FORCEADD CAP_A..1
(-4950 850);
FORCEPROP 1 LAST PART_NUMBER A36096-030
J 0
(-4900 700);
DISPLAY 0.617021 (-4900 700);
PAINT BLUE (-4900 700);
FORCEPROP 1 LASTPIN (-4950 750) $PN 2
J 0
(-4940 730);
DISPLAY 0.617021 (-4940 730);
PAINT ORANGE (-4940 730);
FORCEPROP 1 LASTPIN (-4950 950) $PN 1
J 0
(-4940 930);
DISPLAY 0.617021 (-4940 930);
PAINT ORANGE (-4940 930);
FORCEPROP 1 LAST PACK_TYPE 0402V
J 0
(-4900 650);
DISPLAY 0.617021 (-4900 650);
PAINT SKYBLUE (-4900 650);
FORCEPROP 1 LAST LOCATION C1T3
J 0
(-4900 950);
DISPLAY 0.617021 (-4900 950);
PAINT AQUA (-4900 950);
FORCEPROP 1 LAST MATERIAL X7R
J 0
(-4900 750);
DISPLAY 0.617021 (-4900 750);
PAINT SKYBLUE (-4900 750);
FORCEPROP 1 LAST TOLERANCE 10%
J 0
(-4900 800);
DISPLAY 0.617021 (-4900 800);
PAINT SKYBLUE (-4900 800);
FORCEPROP 1 LAST VOLTAGE 16V
J 0
(-4900 850);
DISPLAY 0.617021 (-4900 850);
PAINT SKYBLUE (-4900 850);
FORCEPROP 1 LAST VALUE 0.1UF
J 0
(-4900 900);
DISPLAY 0.617021 (-4900 900);
PAINT SKYBLUE (-4900 900);
FORCEPROP 0 LAST GROUP NI_I210&RJ45
J 0
(-4894 563);
DISPLAY 0.638298 (-4894 563);
PAINT BROWN (-4894 563);
DISPLAY BOTH (-4894 563);
FORCEPROP 2 LAST CDS_LOCATION C1T3
J 0
(-4900 950);
DISPLAY 0.617021 (-4900 950);
PAINT AQUA (-4900 950);
DISPLAY INVISIBLE (-4900 950);
FORCEPROP 2 LAST CDS_LIB dev_discrete
J 0
(-4950 850);
PAINT ORANGE (-4950 850);
DISPLAY INVISIBLE (-4950 850);
FORCEPROP 1 LAST PATH I144
J 0
(-4900 1000);
DISPLAY 0.978723 (-4900 1000);
PAINT WHITE (-4900 1000);
DISPLAY INVISIBLE (-4900 1000);
FORCEPROP 2 LAST ROOM NIC_SPRV
J 0
(-4900 1000);
DISPLAY 1.021277 (-4900 1000);
PAINT ORANGE (-4900 1000);
DISPLAY INVISIBLE (-4900 1000);
FORCEPROP 2 LAST BOM_COST NT_GBE_BASE
J 0
(-4900 1050);
DISPLAY 1.021277 (-4900 1050);
PAINT ORANGE (-4900 1050);
DISPLAY INVISIBLE (-4900 1050);
FORCEPROP 2 LAST $SEC 1
J 0
(-4900 1050);
PAINT MONO (-4900 1050);
DISPLAY INVISIBLE (-4900 1050);
FORCEPROP 2 LAST CDS_SEC 1
J 0
(-4900 1050);
PAINT MONO (-4900 1050);
DISPLAY INVISIBLE (-4900 1050);
FORCEADD CAP_A..1
(-4700 850);
FORCEPROP 1 LAST LOCATION C1R14
J 0
(-4650 950);
DISPLAY 0.617021 (-4650 950);
PAINT AQUA (-4650 950);
FORCEPROP 1 LAST PART_NUMBER A36096-030
J 0
(-4650 700);
DISPLAY 0.617021 (-4650 700);
PAINT BLUE (-4650 700);
FORCEPROP 1 LAST TOLERANCE 10%
J 0
(-4650 800);
DISPLAY 0.617021 (-4650 800);
PAINT SKYBLUE (-4650 800);
FORCEPROP 1 LASTPIN (-4700 750) $PN 2
J 0
(-4690 730);
DISPLAY 0.617021 (-4690 730);
PAINT ORANGE (-4690 730);
FORCEPROP 1 LAST VOLTAGE 16V
J 0
(-4650 850);
DISPLAY 0.617021 (-4650 850);
PAINT SKYBLUE (-4650 850);
FORCEPROP 1 LAST VALUE 0.1UF
J 0
(-4650 900);
DISPLAY 0.617021 (-4650 900);
PAINT SKYBLUE (-4650 900);
FORCEPROP 1 LAST MATERIAL X7R
J 0
(-4650 750);
DISPLAY 0.617021 (-4650 750);
PAINT SKYBLUE (-4650 750);
FORCEPROP 1 LAST PACK_TYPE 0402V
J 0
(-4650 650);
DISPLAY 0.617021 (-4650 650);
PAINT SKYBLUE (-4650 650);
FORCEPROP 1 LASTPIN (-4700 950) $PN 1
J 0
(-4690 930);
DISPLAY 0.617021 (-4690 930);
PAINT ORANGE (-4690 930);
FORCEPROP 0 LAST GROUP NI_I210&RJ45
J 0
(-4644 513);
DISPLAY 0.638298 (-4644 513);
PAINT BROWN (-4644 513);
DISPLAY BOTH (-4644 513);
FORCEPROP 2 LAST CDS_LOCATION C1R14
J 0
(-4650 950);
DISPLAY 0.617021 (-4650 950);
PAINT AQUA (-4650 950);
DISPLAY INVISIBLE (-4650 950);
FORCEPROP 2 LAST CDS_LIB dev_discrete
J 0
(-4700 850);
PAINT ORANGE (-4700 850);
DISPLAY INVISIBLE (-4700 850);
FORCEPROP 2 LAST $SEC 1
J 0
(-4650 1050);
PAINT MONO (-4650 1050);
DISPLAY INVISIBLE (-4650 1050);
FORCEPROP 2 LAST CDS_SEC 1
J 0
(-4650 1050);
PAINT MONO (-4650 1050);
DISPLAY INVISIBLE (-4650 1050);
FORCEPROP 2 LAST BOM_COST NT_GBE_BASE
J 0
(-4650 1050);
DISPLAY 1.021277 (-4650 1050);
PAINT ORANGE (-4650 1050);
DISPLAY INVISIBLE (-4650 1050);
FORCEPROP 2 LAST ROOM NIC_SPRV
J 0
(-4650 1000);
DISPLAY 1.021277 (-4650 1000);
PAINT ORANGE (-4650 1000);
DISPLAY INVISIBLE (-4650 1000);
FORCEPROP 1 LAST PATH I145
J 0
(-4650 1000);
DISPLAY 0.978723 (-4650 1000);
PAINT WHITE (-4650 1000);
DISPLAY INVISIBLE (-4650 1000);
FORCEADD CAP_A..1
(-4450 850);
FORCEPROP 1 LAST PACK_TYPE 0402V
J 0
(-4400 650);
DISPLAY 0.617021 (-4400 650);
PAINT SKYBLUE (-4400 650);
FORCEPROP 1 LAST VOLTAGE 16V
J 0
(-4400 850);
DISPLAY 0.617021 (-4400 850);
PAINT SKYBLUE (-4400 850);
FORCEPROP 1 LAST TOLERANCE 10%
J 0
(-4400 800);
DISPLAY 0.617021 (-4400 800);
PAINT SKYBLUE (-4400 800);
FORCEPROP 1 LAST MATERIAL X7R
J 0
(-4400 750);
DISPLAY 0.617021 (-4400 750);
PAINT SKYBLUE (-4400 750);
FORCEPROP 1 LASTPIN (-4450 950) $PN 1
J 0
(-4440 930);
DISPLAY 0.617021 (-4440 930);
PAINT ORANGE (-4440 930);
FORCEPROP 1 LAST VALUE 0.1UF
J 0
(-4400 900);
DISPLAY 0.617021 (-4400 900);
PAINT SKYBLUE (-4400 900);
FORCEPROP 1 LAST LOCATION C1R21
J 0
(-4400 950);
DISPLAY 0.617021 (-4400 950);
PAINT AQUA (-4400 950);
FORCEPROP 1 LASTPIN (-4450 750) $PN 2
J 0
(-4440 730);
DISPLAY 0.617021 (-4440 730);
PAINT ORANGE (-4440 730);
FORCEPROP 1 LAST PART_NUMBER A36096-030
J 0
(-4400 700);
DISPLAY 0.617021 (-4400 700);
PAINT BLUE (-4400 700);
FORCEPROP 0 LAST GROUP NI_I210&RJ45
J 0
(-4394 563);
DISPLAY 0.638298 (-4394 563);
PAINT BROWN (-4394 563);
DISPLAY BOTH (-4394 563);
FORCEPROP 2 LAST CDS_LOCATION C1R21
J 0
(-4400 950);
DISPLAY 0.617021 (-4400 950);
PAINT AQUA (-4400 950);
DISPLAY INVISIBLE (-4400 950);
FORCEPROP 2 LAST CDS_LIB dev_discrete
J 0
(-4450 850);
PAINT ORANGE (-4450 850);
DISPLAY INVISIBLE (-4450 850);
FORCEPROP 2 LAST $SEC 1
J 0
(-4400 1050);
PAINT MONO (-4400 1050);
DISPLAY INVISIBLE (-4400 1050);
FORCEPROP 2 LAST CDS_SEC 1
J 0
(-4400 1050);
PAINT MONO (-4400 1050);
DISPLAY INVISIBLE (-4400 1050);
FORCEPROP 2 LAST BOM_COST NT_GBE_BASE
J 0
(-4400 1050);
DISPLAY 1.021277 (-4400 1050);
PAINT ORANGE (-4400 1050);
DISPLAY INVISIBLE (-4400 1050);
FORCEPROP 2 LAST ROOM NIC_SPRV
J 0
(-4400 1000);
DISPLAY 1.021277 (-4400 1000);
PAINT ORANGE (-4400 1000);
DISPLAY INVISIBLE (-4400 1000);
FORCEPROP 1 LAST PATH I146
J 0
(-4400 1000);
DISPLAY 0.978723 (-4400 1000);
PAINT WHITE (-4400 1000);
DISPLAY INVISIBLE (-4400 1000);
FORCEADD CAP_A..1
(-2325 875);
FORCEPROP 1 LAST TOLERANCE 10%
J 0
(-2275 825);
DISPLAY 0.617021 (-2275 825);
PAINT SKYBLUE (-2275 825);
FORCEPROP 1 LASTPIN (-2325 975) $PN 1
J 0
(-2315 955);
DISPLAY 0.617021 (-2315 955);
PAINT ORANGE (-2315 955);
FORCEPROP 1 LAST LOCATION C1R26
J 0
(-2275 975);
DISPLAY 0.617021 (-2275 975);
PAINT AQUA (-2275 975);
FORCEPROP 1 LAST PACK_TYPE 0402V
J 0
(-2275 675);
DISPLAY 0.617021 (-2275 675);
PAINT SKYBLUE (-2275 675);
FORCEPROP 1 LAST PART_NUMBER A36096-030
J 0
(-2275 725);
DISPLAY 0.617021 (-2275 725);
PAINT BLUE (-2275 725);
FORCEPROP 1 LASTPIN (-2325 775) $PN 2
J 0
(-2315 755);
DISPLAY 0.617021 (-2315 755);
PAINT ORANGE (-2315 755);
FORCEPROP 1 LAST MATERIAL X7R
J 0
(-2275 775);
DISPLAY 0.617021 (-2275 775);
PAINT SKYBLUE (-2275 775);
FORCEPROP 1 LAST VALUE 0.1UF
J 0
(-2275 925);
DISPLAY 0.617021 (-2275 925);
PAINT SKYBLUE (-2275 925);
FORCEPROP 1 LAST VOLTAGE 16V
J 0
(-2275 875);
DISPLAY 0.617021 (-2275 875);
PAINT SKYBLUE (-2275 875);
FORCEPROP 0 LAST GROUP NI_I210&RJ45
J 0
(-2269 563);
DISPLAY 0.638298 (-2269 563);
PAINT BROWN (-2269 563);
DISPLAY BOTH (-2269 563);
FORCEPROP 2 LAST CDS_LIB dev_discrete
J 0
(-2325 875);
PAINT ORANGE (-2325 875);
DISPLAY INVISIBLE (-2325 875);
FORCEPROP 2 LAST CDS_LOCATION C1R26
J 0
(-2275 975);
DISPLAY 0.617021 (-2275 975);
PAINT AQUA (-2275 975);
DISPLAY INVISIBLE (-2275 975);
FORCEPROP 2 LAST $SEC 1
J 0
(-2275 1075);
PAINT MONO (-2275 1075);
DISPLAY INVISIBLE (-2275 1075);
FORCEPROP 2 LAST CDS_SEC 1
J 0
(-2275 1075);
PAINT MONO (-2275 1075);
DISPLAY INVISIBLE (-2275 1075);
FORCEPROP 2 LAST BOM_COST NT_GBE_BASE
J 0
(-2275 1075);
DISPLAY 1.021277 (-2275 1075);
PAINT ORANGE (-2275 1075);
DISPLAY INVISIBLE (-2275 1075);
FORCEPROP 2 LAST ROOM NIC_SPRV
J 0
(-2275 1025);
DISPLAY 1.021277 (-2275 1025);
PAINT ORANGE (-2275 1025);
DISPLAY INVISIBLE (-2275 1025);
FORCEPROP 1 LAST PATH I149
J 0
(-2275 1025);
DISPLAY 0.978723 (-2275 1025);
PAINT WHITE (-2275 1025);
DISPLAY INVISIBLE (-2275 1025);
FORCEADD CAP_A..1
(-2575 875);
FORCEPROP 1 LAST MATERIAL X7R
J 0
(-2525 775);
DISPLAY 0.617021 (-2525 775);
PAINT SKYBLUE (-2525 775);
FORCEPROP 1 LASTPIN (-2575 975) $PN 1
J 0
(-2565 955);
DISPLAY 0.617021 (-2565 955);
PAINT ORANGE (-2565 955);
FORCEPROP 1 LAST LOCATION C1R29
J 0
(-2525 975);
DISPLAY 0.617021 (-2525 975);
PAINT AQUA (-2525 975);
FORCEPROP 1 LAST PACK_TYPE 0402V
J 0
(-2525 675);
DISPLAY 0.617021 (-2525 675);
PAINT SKYBLUE (-2525 675);
FORCEPROP 1 LASTPIN (-2575 775) $PN 2
J 0
(-2565 755);
DISPLAY 0.617021 (-2565 755);
PAINT ORANGE (-2565 755);
FORCEPROP 1 LAST PART_NUMBER A36096-030
J 0
(-2525 725);
DISPLAY 0.617021 (-2525 725);
PAINT BLUE (-2525 725);
FORCEPROP 1 LAST TOLERANCE 10%
J 0
(-2525 825);
DISPLAY 0.617021 (-2525 825);
PAINT SKYBLUE (-2525 825);
FORCEPROP 1 LAST VOLTAGE 16V
J 0
(-2525 875);
DISPLAY 0.617021 (-2525 875);
PAINT SKYBLUE (-2525 875);
FORCEPROP 1 LAST VALUE 0.1UF
J 0
(-2525 925);
DISPLAY 0.617021 (-2525 925);
PAINT SKYBLUE (-2525 925);
FORCEPROP 0 LAST GROUP NI_I210&RJ45
J 0
(-2519 513);
DISPLAY 0.638298 (-2519 513);
PAINT BROWN (-2519 513);
DISPLAY BOTH (-2519 513);
FORCEPROP 2 LAST CDS_LIB dev_discrete
J 0
(-2575 875);
PAINT ORANGE (-2575 875);
DISPLAY INVISIBLE (-2575 875);
FORCEPROP 2 LAST CDS_LOCATION C1R29
J 0
(-2525 975);
DISPLAY 0.617021 (-2525 975);
PAINT AQUA (-2525 975);
DISPLAY INVISIBLE (-2525 975);
FORCEPROP 2 LAST $SEC 1
J 0
(-2525 1075);
PAINT MONO (-2525 1075);
DISPLAY INVISIBLE (-2525 1075);
FORCEPROP 2 LAST CDS_SEC 1
J 0
(-2525 1075);
PAINT MONO (-2525 1075);
DISPLAY INVISIBLE (-2525 1075);
FORCEPROP 2 LAST BOM_COST NT_GBE_BASE
J 0
(-2525 1075);
DISPLAY 1.021277 (-2525 1075);
PAINT ORANGE (-2525 1075);
DISPLAY INVISIBLE (-2525 1075);
FORCEPROP 2 LAST ROOM NIC_SPRV
J 0
(-2525 1025);
DISPLAY 1.021277 (-2525 1025);
PAINT ORANGE (-2525 1025);
DISPLAY INVISIBLE (-2525 1025);
FORCEPROP 1 LAST PATH I150
J 0
(-2525 1025);
DISPLAY 0.978723 (-2525 1025);
PAINT WHITE (-2525 1025);
DISPLAY INVISIBLE (-2525 1025);
FORCEADD CAP_A..1
(-2825 875);
FORCEPROP 1 LAST VOLTAGE 16V
J 0
(-2775 875);
DISPLAY 0.617021 (-2775 875);
PAINT SKYBLUE (-2775 875);
FORCEPROP 1 LASTPIN (-2825 975) $PN 1
J 0
(-2815 955);
DISPLAY 0.617021 (-2815 955);
PAINT ORANGE (-2815 955);
FORCEPROP 1 LAST VALUE 0.1UF
J 0
(-2775 925);
DISPLAY 0.617021 (-2775 925);
PAINT SKYBLUE (-2775 925);
FORCEPROP 1 LAST TOLERANCE 10%
J 0
(-2775 825);
DISPLAY 0.617021 (-2775 825);
PAINT SKYBLUE (-2775 825);
FORCEPROP 1 LAST MATERIAL X7R
J 0
(-2775 775);
DISPLAY 0.617021 (-2775 775);
PAINT SKYBLUE (-2775 775);
FORCEPROP 1 LASTPIN (-2825 775) $PN 2
J 0
(-2815 755);
DISPLAY 0.617021 (-2815 755);
PAINT ORANGE (-2815 755);
FORCEPROP 1 LAST PART_NUMBER A36096-030
J 0
(-2775 725);
DISPLAY 0.617021 (-2775 725);
PAINT BLUE (-2775 725);
FORCEPROP 1 LAST PACK_TYPE 0402V
J 0
(-2775 675);
DISPLAY 0.617021 (-2775 675);
PAINT SKYBLUE (-2775 675);
FORCEPROP 1 LAST LOCATION C1R19
J 0
(-2775 975);
DISPLAY 0.617021 (-2775 975);
PAINT AQUA (-2775 975);
FORCEPROP 0 LAST GROUP NI_I210&RJ45
J 0
(-2769 563);
DISPLAY 0.638298 (-2769 563);
PAINT BROWN (-2769 563);
DISPLAY BOTH (-2769 563);
FORCEPROP 2 LAST CDS_LIB dev_discrete
J 0
(-2825 875);
PAINT ORANGE (-2825 875);
DISPLAY INVISIBLE (-2825 875);
FORCEPROP 2 LAST CDS_LOCATION C1R19
J 0
(-2775 975);
DISPLAY 0.617021 (-2775 975);
PAINT AQUA (-2775 975);
DISPLAY INVISIBLE (-2775 975);
FORCEPROP 2 LAST $SEC 1
J 0
(-2775 1075);
PAINT MONO (-2775 1075);
DISPLAY INVISIBLE (-2775 1075);
FORCEPROP 2 LAST CDS_SEC 1
J 0
(-2775 1075);
PAINT MONO (-2775 1075);
DISPLAY INVISIBLE (-2775 1075);
FORCEPROP 2 LAST BOM_COST NT_GBE_BASE
J 0
(-2775 1075);
DISPLAY 1.021277 (-2775 1075);
PAINT ORANGE (-2775 1075);
DISPLAY INVISIBLE (-2775 1075);
FORCEPROP 2 LAST ROOM NIC_SPRV
J 0
(-2775 1025);
DISPLAY 1.021277 (-2775 1025);
PAINT ORANGE (-2775 1025);
DISPLAY INVISIBLE (-2775 1025);
FORCEPROP 1 LAST PATH I151
J 0
(-2775 1025);
DISPLAY 0.978723 (-2775 1025);
PAINT WHITE (-2775 1025);
DISPLAY INVISIBLE (-2775 1025);
FORCEADD CAP_A..1
(-3075 875);
FORCEPROP 1 LAST LOCATION C1R31
J 0
(-3025 975);
DISPLAY 0.617021 (-3025 975);
PAINT AQUA (-3025 975);
FORCEPROP 1 LASTPIN (-3075 975) $PN 1
J 0
(-3065 955);
DISPLAY 0.617021 (-3065 955);
PAINT ORANGE (-3065 955);
FORCEPROP 1 LAST VALUE 0.1UF
J 0
(-3025 925);
DISPLAY 0.617021 (-3025 925);
PAINT SKYBLUE (-3025 925);
FORCEPROP 1 LAST VOLTAGE 16V
J 0
(-3025 875);
DISPLAY 0.617021 (-3025 875);
PAINT SKYBLUE (-3025 875);
FORCEPROP 1 LAST TOLERANCE 10%
J 0
(-3025 825);
DISPLAY 0.617021 (-3025 825);
PAINT SKYBLUE (-3025 825);
FORCEPROP 1 LAST PART_NUMBER A36096-030
J 0
(-3025 725);
DISPLAY 0.617021 (-3025 725);
PAINT BLUE (-3025 725);
FORCEPROP 1 LAST MATERIAL X7R
J 0
(-3025 775);
DISPLAY 0.617021 (-3025 775);
PAINT SKYBLUE (-3025 775);
FORCEPROP 1 LASTPIN (-3075 775) $PN 2
J 0
(-3065 755);
DISPLAY 0.617021 (-3065 755);
PAINT ORANGE (-3065 755);
FORCEPROP 1 LAST PACK_TYPE 0402V
J 0
(-3025 675);
DISPLAY 0.617021 (-3025 675);
PAINT SKYBLUE (-3025 675);
FORCEPROP 0 LAST GROUP NI_I210&RJ45
J 0
(-3019 513);
DISPLAY 0.638298 (-3019 513);
PAINT BROWN (-3019 513);
DISPLAY BOTH (-3019 513);
FORCEPROP 2 LAST CDS_LIB dev_discrete
J 0
(-3075 875);
PAINT ORANGE (-3075 875);
DISPLAY INVISIBLE (-3075 875);
FORCEPROP 2 LAST $SEC 1
J 0
(-3025 1075);
PAINT MONO (-3025 1075);
DISPLAY INVISIBLE (-3025 1075);
FORCEPROP 2 LAST CDS_SEC 1
J 0
(-3025 1075);
PAINT MONO (-3025 1075);
DISPLAY INVISIBLE (-3025 1075);
FORCEPROP 2 LAST BOM_COST NT_GBE_BASE
J 0
(-3025 1075);
DISPLAY 1.021277 (-3025 1075);
PAINT ORANGE (-3025 1075);
DISPLAY INVISIBLE (-3025 1075);
FORCEPROP 2 LAST ROOM NIC_SPRV
J 0
(-3025 1025);
DISPLAY 1.021277 (-3025 1025);
PAINT ORANGE (-3025 1025);
DISPLAY INVISIBLE (-3025 1025);
FORCEPROP 1 LAST PATH I152
J 0
(-3025 1025);
DISPLAY 0.978723 (-3025 1025);
PAINT WHITE (-3025 1025);
DISPLAY INVISIBLE (-3025 1025);
FORCEADD CAP..1
(-3325 875);
FORCEPROP 1 LAST VALUE 10UF
J 0
(-3275 925);
DISPLAY 0.617021 (-3275 925);
PAINT SKYBLUE (-3275 925);
FORCEPROP 1 LASTPIN (-3325 975) $PN 1
J 0
(-3315 955);
DISPLAY 0.617021 (-3315 955);
PAINT ORANGE (-3315 955);
FORCEPROP 1 LAST MATERIAL X6S
J 0
(-3275 775);
DISPLAY 0.617021 (-3275 775);
PAINT SKYBLUE (-3275 775);
FORCEPROP 1 LASTPIN (-3325 775) $PN 2
J 0
(-3315 755);
DISPLAY 0.617021 (-3315 755);
PAINT ORANGE (-3315 755);
FORCEPROP 1 LAST LOCATION C1R17
J 0
(-3275 975);
DISPLAY 0.617021 (-3275 975);
PAINT AQUA (-3275 975);
FORCEPROP 1 LAST VOLTAGE 6.3V
J 0
(-3275 875);
DISPLAY 0.617021 (-3275 875);
PAINT SKYBLUE (-3275 875);
FORCEPROP 1 LAST PART_NUMBER E15431-002
J 0
(-3275 725);
DISPLAY 0.617021 (-3275 725);
PAINT BLUE (-3275 725);
FORCEPROP 1 LAST PACK_TYPE 0603
J 0
(-3275 675);
DISPLAY 0.617021 (-3275 675);
PAINT SKYBLUE (-3275 675);
FORCEPROP 1 LAST TOLERANCE 20%
J 0
(-3275 825);
DISPLAY 0.617021 (-3275 825);
PAINT SKYBLUE (-3275 825);
FORCEPROP 0 LAST GROUP NI_I210&RJ45
J 0
(-3269 563);
DISPLAY 0.638298 (-3269 563);
PAINT BROWN (-3269 563);
DISPLAY BOTH (-3269 563);
FORCEPROP 2 LAST CDS_LOCATION C1R17
J 0
(-3275 975);
DISPLAY 0.617021 (-3275 975);
PAINT AQUA (-3275 975);
DISPLAY INVISIBLE (-3275 975);
FORCEPROP 2 LAST CDS_LIB mstr_discrete
J 0
(-3325 875);
PAINT ORANGE (-3325 875);
DISPLAY INVISIBLE (-3325 875);
FORCEPROP 2 LAST $SEC 1
J 0
(-3275 1075);
PAINT MONO (-3275 1075);
DISPLAY INVISIBLE (-3275 1075);
FORCEPROP 2 LAST CDS_SEC 1
J 0
(-3275 1075);
PAINT MONO (-3275 1075);
DISPLAY INVISIBLE (-3275 1075);
FORCEPROP 2 LAST BOM_COST NT_GBE_BASE
J 0
(-3275 1075);
DISPLAY 1.021277 (-3275 1075);
PAINT ORANGE (-3275 1075);
DISPLAY INVISIBLE (-3275 1075);
FORCEPROP 2 LAST ROOM NIC_SPRV
J 0
(-3275 1025);
DISPLAY 1.021277 (-3275 1025);
PAINT ORANGE (-3275 1025);
DISPLAY INVISIBLE (-3275 1025);
FORCEPROP 1 LAST PATH I153
J 0
(-3275 1025);
DISPLAY 0.978723 (-3275 1025);
PAINT WHITE (-3275 1025);
DISPLAY INVISIBLE (-3275 1025);
FORCEADD P1V5_LAN..1
(-4150 1200);
FORCEPROP 3 LASTPIN (-4150 1150) SIG_NAME P1V5_LAN\g
J 0
(-4140 1160);
DISPLAY 0.659574 (-4140 1160);
PAINT MONO (-4140 1160);
DISPLAY INVISIBLE (-4140 1160);
FORCEPROP 1 LAST HDL_POWER P1V5_LAN
J 1
(-4150 1250);
DISPLAY 0.872340 (-4150 1250);
PAINT GREEN (-4150 1250);
DISPLAY INVISIBLE (-4150 1250);
FORCEPROP 1 LAST BODY_TYPE PLUMBING
J 0
(-4195 1157);
DISPLAY 0.340426 (-4195 1157);
PAINT GREEN (-4195 1157);
DISPLAY INVISIBLE (-4195 1157);
FORCEPROP 1 LAST PATH I154
J 0
(-4100 1225);
DISPLAY 0.872340 (-4100 1225);
PAINT AQUA (-4100 1225);
DISPLAY INVISIBLE (-4100 1225);
FORCEPROP 2 LAST CDS_LIB mstr_symbols
J 0
(-4150 1200);
PAINT ORANGE (-4150 1200);
DISPLAY INVISIBLE (-4150 1200);
FORCEPROP 1 LAST VOLTAGE 1.5V
J 0
(-4195 1157);
DISPLAY 0.340426 (-4195 1157);
PAINT SKYBLUE (-4195 1157);
DISPLAY INVISIBLE (-4195 1157);
FORCEADD CAP_A..1
(-350 875);
FORCEPROP 0 LAST GROUP NI_I210&RJ45
J 0
(-294 613);
DISPLAY 0.638298 (-294 613);
PAINT BROWN (-294 613);
DISPLAY BOTH (-294 613);
FORCEPROP 1 LAST PART_NUMBER A36096-030
J 0
(-300 725);
DISPLAY 0.617021 (-300 725);
PAINT BLUE (-300 725);
FORCEPROP 1 LASTPIN (-350 775) $PN 2
J 0
(-340 755);
DISPLAY 0.617021 (-340 755);
PAINT ORANGE (-340 755);
FORCEPROP 1 LASTPIN (-350 975) $PN 1
J 0
(-340 955);
DISPLAY 0.617021 (-340 955);
PAINT ORANGE (-340 955);
FORCEPROP 1 LAST VALUE 0.1UF
J 0
(-300 925);
DISPLAY 0.617021 (-300 925);
PAINT SKYBLUE (-300 925);
FORCEPROP 1 LAST TOLERANCE 10%
J 0
(-300 825);
DISPLAY 0.617021 (-300 825);
PAINT SKYBLUE (-300 825);
FORCEPROP 1 LAST LOCATION C1R18
J 0
(-300 975);
DISPLAY 0.617021 (-300 975);
PAINT AQUA (-300 975);
FORCEPROP 1 LAST MATERIAL X7R
J 0
(-300 775);
DISPLAY 0.617021 (-300 775);
PAINT SKYBLUE (-300 775);
FORCEPROP 1 LAST PACK_TYPE 0402V
J 0
(-300 675);
DISPLAY 0.617021 (-300 675);
PAINT SKYBLUE (-300 675);
FORCEPROP 1 LAST VOLTAGE 16V
J 0
(-300 875);
DISPLAY 0.617021 (-300 875);
PAINT SKYBLUE (-300 875);
FORCEPROP 2 LAST CDS_LIB dev_discrete
J 0
(-350 875);
PAINT ORANGE (-350 875);
DISPLAY INVISIBLE (-350 875);
FORCEPROP 2 LAST CDS_LOCATION C1R18
J 0
(-300 975);
DISPLAY 0.617021 (-300 975);
PAINT AQUA (-300 975);
DISPLAY INVISIBLE (-300 975);
FORCEPROP 2 LAST $SEC 1
J 0
(-300 1075);
PAINT MONO (-300 1075);
DISPLAY INVISIBLE (-300 1075);
FORCEPROP 2 LAST CDS_SEC 1
J 0
(-300 1075);
PAINT MONO (-300 1075);
DISPLAY INVISIBLE (-300 1075);
FORCEPROP 2 LAST BOM_COST NT_GBE_BASE
J 0
(-300 1075);
DISPLAY 1.021277 (-300 1075);
PAINT ORANGE (-300 1075);
DISPLAY INVISIBLE (-300 1075);
FORCEPROP 2 LAST ROOM NIC_SPRV
J 0
(-300 1025);
DISPLAY 1.021277 (-300 1025);
PAINT ORANGE (-300 1025);
DISPLAY INVISIBLE (-300 1025);
FORCEPROP 1 LAST PATH I157
J 0
(-300 1025);
DISPLAY 0.978723 (-300 1025);
PAINT WHITE (-300 1025);
DISPLAY INVISIBLE (-300 1025);
FORCEADD CAP_A..1
(-600 875);
FORCEPROP 1 LAST LOCATION C1T5
J 0
(-550 975);
DISPLAY 0.617021 (-550 975);
PAINT AQUA (-550 975);
FORCEPROP 1 LAST VALUE 0.1UF
J 0
(-550 925);
DISPLAY 0.617021 (-550 925);
PAINT SKYBLUE (-550 925);
FORCEPROP 1 LAST VOLTAGE 16V
J 0
(-550 875);
DISPLAY 0.617021 (-550 875);
PAINT SKYBLUE (-550 875);
FORCEPROP 1 LAST TOLERANCE 10%
J 0
(-550 825);
DISPLAY 0.617021 (-550 825);
PAINT SKYBLUE (-550 825);
FORCEPROP 1 LAST PACK_TYPE 0402V
J 0
(-550 675);
DISPLAY 0.617021 (-550 675);
PAINT SKYBLUE (-550 675);
FORCEPROP 1 LAST PART_NUMBER A36096-030
J 0
(-550 725);
DISPLAY 0.617021 (-550 725);
PAINT BLUE (-550 725);
FORCEPROP 1 LASTPIN (-600 975) $PN 1
J 0
(-590 955);
DISPLAY 0.617021 (-590 955);
PAINT ORANGE (-590 955);
FORCEPROP 1 LASTPIN (-600 775) $PN 2
J 0
(-590 755);
DISPLAY 0.617021 (-590 755);
PAINT ORANGE (-590 755);
FORCEPROP 1 LAST MATERIAL X7R
J 0
(-550 775);
DISPLAY 0.617021 (-550 775);
PAINT SKYBLUE (-550 775);
FORCEPROP 0 LAST GROUP NI_I210&RJ45
J 0
(-544 563);
DISPLAY 0.638298 (-544 563);
PAINT BROWN (-544 563);
DISPLAY BOTH (-544 563);
FORCEPROP 2 LAST CDS_LOCATION C1T5
J 0
(-550 975);
DISPLAY 0.617021 (-550 975);
PAINT AQUA (-550 975);
DISPLAY INVISIBLE (-550 975);
FORCEPROP 2 LAST CDS_LIB dev_discrete
J 0
(-600 875);
PAINT ORANGE (-600 875);
DISPLAY INVISIBLE (-600 875);
FORCEPROP 2 LAST $SEC 1
J 0
(-550 1075);
PAINT MONO (-550 1075);
DISPLAY INVISIBLE (-550 1075);
FORCEPROP 2 LAST CDS_SEC 1
J 0
(-550 1075);
PAINT MONO (-550 1075);
DISPLAY INVISIBLE (-550 1075);
FORCEPROP 2 LAST BOM_COST NT_GBE_BASE
J 0
(-550 1075);
DISPLAY 1.021277 (-550 1075);
PAINT ORANGE (-550 1075);
DISPLAY INVISIBLE (-550 1075);
FORCEPROP 2 LAST ROOM NIC_SPRV
J 0
(-550 1025);
DISPLAY 1.021277 (-550 1025);
PAINT ORANGE (-550 1025);
DISPLAY INVISIBLE (-550 1025);
FORCEPROP 1 LAST PATH I158
J 0
(-550 1025);
DISPLAY 0.978723 (-550 1025);
PAINT WHITE (-550 1025);
DISPLAY INVISIBLE (-550 1025);
FORCEADD CAP_A..1
(-850 875);
FORCEPROP 0 LAST GROUP NI_I210&RJ45
J 0
(-794 613);
DISPLAY 0.638298 (-794 613);
PAINT BROWN (-794 613);
DISPLAY BOTH (-794 613);
FORCEPROP 1 LAST LOCATION C1R24
J 0
(-800 975);
DISPLAY 0.617021 (-800 975);
PAINT AQUA (-800 975);
FORCEPROP 1 LAST VALUE 0.1UF
J 0
(-800 925);
DISPLAY 0.617021 (-800 925);
PAINT SKYBLUE (-800 925);
FORCEPROP 1 LAST MATERIAL X7R
J 0
(-800 775);
DISPLAY 0.617021 (-800 775);
PAINT SKYBLUE (-800 775);
FORCEPROP 1 LASTPIN (-850 975) $PN 1
J 0
(-840 955);
DISPLAY 0.617021 (-840 955);
PAINT ORANGE (-840 955);
FORCEPROP 1 LAST TOLERANCE 10%
J 0
(-800 825);
DISPLAY 0.617021 (-800 825);
PAINT SKYBLUE (-800 825);
FORCEPROP 1 LAST VOLTAGE 16V
J 0
(-800 875);
DISPLAY 0.617021 (-800 875);
PAINT SKYBLUE (-800 875);
FORCEPROP 1 LASTPIN (-850 775) $PN 2
J 0
(-840 755);
DISPLAY 0.617021 (-840 755);
PAINT ORANGE (-840 755);
FORCEPROP 1 LAST PART_NUMBER A36096-030
J 0
(-800 725);
DISPLAY 0.617021 (-800 725);
PAINT BLUE (-800 725);
FORCEPROP 1 LAST PACK_TYPE 0402V
J 0
(-800 675);
DISPLAY 0.617021 (-800 675);
PAINT SKYBLUE (-800 675);
FORCEPROP 2 LAST CDS_LOCATION C1R24
J 0
(-800 975);
DISPLAY 0.617021 (-800 975);
PAINT AQUA (-800 975);
DISPLAY INVISIBLE (-800 975);
FORCEPROP 2 LAST CDS_LIB dev_discrete
J 0
(-850 875);
PAINT ORANGE (-850 875);
DISPLAY INVISIBLE (-850 875);
FORCEPROP 1 LAST PATH I159
J 0
(-800 1025);
DISPLAY 0.978723 (-800 1025);
PAINT WHITE (-800 1025);
DISPLAY INVISIBLE (-800 1025);
FORCEPROP 2 LAST ROOM NIC_SPRV
J 0
(-800 1025);
DISPLAY 1.021277 (-800 1025);
PAINT ORANGE (-800 1025);
DISPLAY INVISIBLE (-800 1025);
FORCEPROP 2 LAST BOM_COST NT_GBE_BASE
J 0
(-800 1075);
DISPLAY 1.021277 (-800 1075);
PAINT ORANGE (-800 1075);
DISPLAY INVISIBLE (-800 1075);
FORCEPROP 2 LAST CDS_SEC 1
J 0
(-800 1075);
PAINT MONO (-800 1075);
DISPLAY INVISIBLE (-800 1075);
FORCEPROP 2 LAST $SEC 1
J 0
(-800 1075);
PAINT MONO (-800 1075);
DISPLAY INVISIBLE (-800 1075);
FORCEADD CAP_A..1
(-1100 875);
FORCEPROP 1 LASTPIN (-1100 775) $PN 2
J 0
(-1090 755);
DISPLAY 0.617021 (-1090 755);
PAINT ORANGE (-1090 755);
FORCEPROP 1 LAST MATERIAL X7R
J 0
(-1050 775);
DISPLAY 0.617021 (-1050 775);
PAINT SKYBLUE (-1050 775);
FORCEPROP 1 LAST VOLTAGE 16V
J 0
(-1050 875);
DISPLAY 0.617021 (-1050 875);
PAINT SKYBLUE (-1050 875);
FORCEPROP 1 LAST TOLERANCE 10%
J 0
(-1050 825);
DISPLAY 0.617021 (-1050 825);
PAINT SKYBLUE (-1050 825);
FORCEPROP 1 LASTPIN (-1100 975) $PN 1
J 0
(-1090 955);
DISPLAY 0.617021 (-1090 955);
PAINT ORANGE (-1090 955);
FORCEPROP 1 LAST VALUE 0.1UF
J 0
(-1050 925);
DISPLAY 0.617021 (-1050 925);
PAINT SKYBLUE (-1050 925);
FORCEPROP 1 LAST LOCATION C1R15
J 0
(-1050 975);
DISPLAY 0.617021 (-1050 975);
PAINT AQUA (-1050 975);
FORCEPROP 1 LAST PART_NUMBER A36096-030
J 0
(-1050 725);
DISPLAY 0.617021 (-1050 725);
PAINT BLUE (-1050 725);
FORCEPROP 1 LAST PACK_TYPE 0402V
J 0
(-1050 675);
DISPLAY 0.617021 (-1050 675);
PAINT SKYBLUE (-1050 675);
FORCEPROP 0 LAST GROUP NI_I210&RJ45
J 0
(-1044 563);
DISPLAY 0.638298 (-1044 563);
PAINT BROWN (-1044 563);
DISPLAY BOTH (-1044 563);
FORCEPROP 2 LAST CDS_LOCATION C1R15
J 0
(-1050 975);
DISPLAY 0.617021 (-1050 975);
PAINT AQUA (-1050 975);
DISPLAY INVISIBLE (-1050 975);
FORCEPROP 2 LAST CDS_LIB dev_discrete
J 0
(-1100 875);
PAINT ORANGE (-1100 875);
DISPLAY INVISIBLE (-1100 875);
FORCEPROP 1 LAST PATH I160
J 0
(-1050 1025);
DISPLAY 0.978723 (-1050 1025);
PAINT WHITE (-1050 1025);
DISPLAY INVISIBLE (-1050 1025);
FORCEPROP 2 LAST ROOM NIC_SPRV
J 0
(-1050 1025);
DISPLAY 1.021277 (-1050 1025);
PAINT ORANGE (-1050 1025);
DISPLAY INVISIBLE (-1050 1025);
FORCEPROP 2 LAST BOM_COST NT_GBE_BASE
J 0
(-1050 1075);
DISPLAY 1.021277 (-1050 1075);
PAINT ORANGE (-1050 1075);
DISPLAY INVISIBLE (-1050 1075);
FORCEPROP 2 LAST CDS_SEC 1
J 0
(-1050 1075);
PAINT MONO (-1050 1075);
DISPLAY INVISIBLE (-1050 1075);
FORCEPROP 2 LAST $SEC 1
J 0
(-1050 1075);
PAINT MONO (-1050 1075);
DISPLAY INVISIBLE (-1050 1075);
FORCEADD CAP..1
(-1350 875);
FORCEPROP 1 LAST VOLTAGE 6.3V
J 0
(-1300 875);
DISPLAY 0.617021 (-1300 875);
PAINT SKYBLUE (-1300 875);
FORCEPROP 1 LAST TOLERANCE 20%
J 0
(-1300 825);
DISPLAY 0.617021 (-1300 825);
PAINT SKYBLUE (-1300 825);
FORCEPROP 1 LAST MATERIAL X6S
J 0
(-1300 775);
DISPLAY 0.617021 (-1300 775);
PAINT SKYBLUE (-1300 775);
FORCEPROP 1 LASTPIN (-1350 975) $PN 1
J 0
(-1340 955);
DISPLAY 0.617021 (-1340 955);
PAINT ORANGE (-1340 955);
FORCEPROP 1 LASTPIN (-1350 775) $PN 2
J 0
(-1340 755);
DISPLAY 0.617021 (-1340 755);
PAINT ORANGE (-1340 755);
FORCEPROP 1 LAST VALUE 10UF
J 0
(-1300 925);
DISPLAY 0.617021 (-1300 925);
PAINT SKYBLUE (-1300 925);
FORCEPROP 1 LAST LOCATION C1R16
J 0
(-1300 975);
DISPLAY 0.617021 (-1300 975);
PAINT AQUA (-1300 975);
FORCEPROP 1 LAST PART_NUMBER E15431-002
J 0
(-1300 725);
DISPLAY 0.617021 (-1300 725);
PAINT BLUE (-1300 725);
FORCEPROP 1 LAST PACK_TYPE 0603
J 0
(-1300 675);
DISPLAY 0.617021 (-1300 675);
PAINT SKYBLUE (-1300 675);
FORCEPROP 0 LAST GROUP NI_I210&RJ45
J 0
(-1294 613);
DISPLAY 0.638298 (-1294 613);
PAINT BROWN (-1294 613);
DISPLAY BOTH (-1294 613);
FORCEPROP 2 LAST CDS_LOCATION C1R16
J 0
(-1300 975);
DISPLAY 0.617021 (-1300 975);
PAINT AQUA (-1300 975);
DISPLAY INVISIBLE (-1300 975);
FORCEPROP 2 LAST CDS_LIB mstr_discrete
J 0
(-1350 875);
PAINT ORANGE (-1350 875);
DISPLAY INVISIBLE (-1350 875);
FORCEPROP 2 LAST BOM_COST NT_GBE_BASE
J 0
(-1300 1075);
DISPLAY 1.021277 (-1300 1075);
PAINT ORANGE (-1300 1075);
DISPLAY INVISIBLE (-1300 1075);
FORCEPROP 2 LAST CDS_SEC 1
J 0
(-1300 1075);
PAINT MONO (-1300 1075);
DISPLAY INVISIBLE (-1300 1075);
FORCEPROP 2 LAST $SEC 1
J 0
(-1300 1075);
PAINT MONO (-1300 1075);
DISPLAY INVISIBLE (-1300 1075);
FORCEPROP 1 LAST PATH I161
J 0
(-1300 1025);
DISPLAY 0.978723 (-1300 1025);
PAINT WHITE (-1300 1025);
DISPLAY INVISIBLE (-1300 1025);
FORCEPROP 2 LAST ROOM NIC_SPRV
J 0
(-1300 1025);
DISPLAY 1.021277 (-1300 1025);
PAINT ORANGE (-1300 1025);
DISPLAY INVISIBLE (-1300 1025);
FORCEADD P0V9_LAN..1
(-1925 1150);
FORCEPROP 3 LASTPIN (-1925 1100) SIG_NAME P0V9_LAN\g
J 0
(-1915 1110);
DISPLAY 0.659574 (-1915 1110);
PAINT MONO (-1915 1110);
DISPLAY INVISIBLE (-1915 1110);
FORCEPROP 1 LAST VOLTAGE 0.9V
J 0
(-1970 1107);
DISPLAY 0.340426 (-1970 1107);
PAINT SKYBLUE (-1970 1107);
DISPLAY INVISIBLE (-1970 1107);
FORCEPROP 2 LAST CDS_LIB mstr_symbols
J 0
(-1925 1150);
PAINT ORANGE (-1925 1150);
DISPLAY INVISIBLE (-1925 1150);
FORCEPROP 1 LAST PATH I162
J 0
(-1875 1175);
DISPLAY 0.872340 (-1875 1175);
PAINT AQUA (-1875 1175);
DISPLAY INVISIBLE (-1875 1175);
FORCEPROP 1 LAST BODY_TYPE PLUMBING
J 0
(-1970 1107);
DISPLAY 0.340426 (-1970 1107);
PAINT GREEN (-1970 1107);
DISPLAY INVISIBLE (-1970 1107);
FORCEPROP 1 LAST HDL_POWER P0V9_LAN
J 1
(-1925 1200);
DISPLAY 0.872340 (-1925 1200);
PAINT GREEN (-1925 1200);
DISPLAY INVISIBLE (-1925 1200);
FORCEADD CAP_A..1
(-1600 875);
FORCEPROP 1 LASTPIN (-1600 975) $PN 1
J 0
(-1590 955);
DISPLAY 0.617021 (-1590 955);
PAINT ORANGE (-1590 955);
FORCEPROP 1 LAST LOCATION C9E1
J 0
(-1550 975);
DISPLAY 0.617021 (-1550 975);
PAINT AQUA (-1550 975);
FORCEPROP 1 LAST MATERIAL EMPTY
J 0
(-1550 775);
DISPLAY 0.617021 (-1550 775);
PAINT RED (-1550 775);
FORCEPROP 1 LAST PART_NUMBER E15431-004
J 0
(-1550 725);
DISPLAY 0.617021 (-1550 725);
PAINT BLUE (-1550 725);
FORCEPROP 1 LAST PACK_TYPE 0603V
J 0
(-1550 675);
DISPLAY 0.617021 (-1550 675);
PAINT SKYBLUE (-1550 675);
FORCEPROP 1 LASTPIN (-1600 775) $PN 2
J 0
(-1590 755);
DISPLAY 0.617021 (-1590 755);
PAINT ORANGE (-1590 755);
FORCEPROP 1 LAST VOLTAGE 4V
J 0
(-1550 875);
DISPLAY 0.617021 (-1550 875);
PAINT SKYBLUE (-1550 875);
FORCEPROP 1 LAST TOLERANCE 20%
J 0
(-1550 825);
DISPLAY 0.617021 (-1550 825);
PAINT SKYBLUE (-1550 825);
FORCEPROP 1 LAST VALUE 22.0UF
J 0
(-1550 925);
DISPLAY 0.617021 (-1550 925);
PAINT SKYBLUE (-1550 925);
FORCEPROP 0 LAST GROUP NI_I210&RJ45
J 0
(-1544 563);
DISPLAY 0.638298 (-1544 563);
PAINT BROWN (-1544 563);
DISPLAY BOTH (-1544 563);
FORCEPROP 2 LAST CDS_LIB dev_discrete
J 0
(-1600 875);
PAINT ORANGE (-1600 875);
DISPLAY INVISIBLE (-1600 875);
FORCEPROP 2 LAST CDS_LOCATION C9E1
J 0
(-1550 975);
DISPLAY 0.617021 (-1550 975);
PAINT AQUA (-1550 975);
DISPLAY INVISIBLE (-1550 975);
FORCEPROP 2 LAST ROOM NIC_SPRV
J 0
(-1550 1025);
DISPLAY 1.021277 (-1550 1025);
PAINT ORANGE (-1550 1025);
DISPLAY INVISIBLE (-1550 1025);
FORCEPROP 1 LAST PATH I163
J 0
(-1550 1025);
DISPLAY 0.978723 (-1550 1025);
PAINT WHITE (-1550 1025);
DISPLAY INVISIBLE (-1550 1025);
FORCEPROP 2 LAST SEC_TYPE 0603V
J 0
(-1550 1075);
DISPLAY 1.021277 (-1550 1075);
PAINT ORANGE (-1550 1075);
DISPLAY INVISIBLE (-1550 1075);
FORCEPROP 2 LAST SEC 1
J 0
(-1550 1075);
DISPLAY 0.680851 (-1550 1075);
PAINT MONO (-1550 1075);
DISPLAY INVISIBLE (-1550 1075);
FORCEPROP 2 LAST BOM_COST NT_GBE_BASE
J 0
(-1550 1075);
DISPLAY 1.021277 (-1550 1075);
PAINT ORANGE (-1550 1075);
DISPLAY INVISIBLE (-1550 1075);
FORCEADD GND..1
(-1925 575);
FORCEPROP 3 LASTPIN (-1925 625) SIG_NAME GND\g
J 0
(-1915 635);
DISPLAY 0.659574 (-1915 635);
PAINT MONO (-1915 635);
DISPLAY INVISIBLE (-1915 635);
FORCEPROP 1 LAST VOLTAGE 0.0V
J 0
(-1970 532);
DISPLAY 0.340426 (-1970 532);
PAINT SKYBLUE (-1970 532);
DISPLAY INVISIBLE (-1970 532);
FORCEPROP 2 LAST CDS_LIB mstr_symbols
J 0
(-1925 575);
PAINT ORANGE (-1925 575);
DISPLAY INVISIBLE (-1925 575);
FORCEPROP 1 LAST SIZE 1B
J 0
(-1850 525);
DISPLAY 0.872340 (-1850 525);
PAINT AQUA (-1850 525);
DISPLAY INVISIBLE (-1850 525);
FORCEPROP 1 LAST PATH I164
J 0
(-1850 575);
DISPLAY 0.872340 (-1850 575);
PAINT AQUA (-1850 575);
DISPLAY INVISIBLE (-1850 575);
FORCEPROP 1 LAST BODY_TYPE PLUMBING
J 0
(-1970 532);
DISPLAY 0.340426 (-1970 532);
PAINT GREEN (-1970 532);
DISPLAY INVISIBLE (-1970 532);
FORCEPROP 1 LAST HDL_POWER GND
J 0
(-1925 725);
DISPLAY 0.872340 (-1925 725);
PAINT GREEN (-1925 725);
DISPLAY INVISIBLE (-1925 725);
FORCEADD OFFPAGE..1
(-6050 3075);
FORCEPROP 2 LAST CDS_LIB mstr_standard
J 0
(-6050 3075);
PAINT ORANGE (-6050 3075);
DISPLAY INVISIBLE (-6050 3075);
FORCEPROP 2 LAST PATH I166
J 0
(-6000 3150);
DISPLAY 1.021277 (-6000 3150);
PAINT ORANGE (-6000 3150);
DISPLAY INVISIBLE (-6000 3150);
FORCEPROP 1 LAST OFFPAGE TRUE
J 0
(-5725 2950);
DISPLAY 0.872340 (-5725 2950);
PAINT GREEN (-5725 2950);
DISPLAY INVISIBLE (-5725 2950);
FORCEPROP 1 LAST COMMENT_BODY TRUE
J 0
(-5925 2975);
DISPLAY 0.872340 (-5925 2975);
PAINT GREEN (-5925 2975);
DISPLAY INVISIBLE (-5925 2975);
FORCEPROP 2 LAST $XR0 139 
J 0
(-6476 3075);
DISPLAY 0.638298 (-6476 3075);
PAINT MONO (-6476 3075);
DISPLAY INVISIBLE (-6476 3075);
FORCEADD OFFPAGE..1
(-6050 3025);
FORCEPROP 2 LAST $XR0 139 
J 0
(-6302 3025);
DISPLAY 0.638298 (-6302 3025);
PAINT MONO (-6302 3025);
FORCEPROP 2 LAST CDS_LIB mstr_standard
J 0
(-6050 3025);
PAINT ORANGE (-6050 3025);
DISPLAY INVISIBLE (-6050 3025);
FORCEPROP 2 LAST PATH I167
J 0
(-6000 3100);
DISPLAY 1.021277 (-6000 3100);
PAINT ORANGE (-6000 3100);
DISPLAY INVISIBLE (-6000 3100);
FORCEPROP 1 LAST OFFPAGE TRUE
J 0
(-5725 2900);
DISPLAY 0.872340 (-5725 2900);
PAINT GREEN (-5725 2900);
DISPLAY INVISIBLE (-5725 2900);
FORCEPROP 1 LAST COMMENT_BODY TRUE
J 0
(-5925 2925);
DISPLAY 0.872340 (-5925 2925);
PAINT GREEN (-5925 2925);
DISPLAY INVISIBLE (-5925 2925);
FORCEADD OFFPAGE..2
(-325 3600);
FORCEPROP 2 LAST $XR0 139 
J 0
(-136 3600);
DISPLAY 0.638298 (-136 3600);
PAINT MONO (-136 3600);
FORCEPROP 2 LAST CDS_LIB mstr_standard
J 0
(-325 3600);
PAINT ORANGE (-325 3600);
DISPLAY INVISIBLE (-325 3600);
FORCEPROP 2 LAST PATH I172
J 0
(-150 3675);
DISPLAY 1.021277 (-150 3675);
PAINT ORANGE (-150 3675);
DISPLAY INVISIBLE (-150 3675);
FORCEPROP 1 LAST OFFPAGE TRUE
J 0
(0 3475);
DISPLAY 0.872340 (0 3475);
PAINT GREEN (0 3475);
DISPLAY INVISIBLE (0 3475);
FORCEPROP 1 LAST COMMENT_BODY TRUE
J 0
(-370 3505);
DISPLAY 0.872340 (-370 3505);
PAINT GREEN (-370 3505);
DISPLAY INVISIBLE (-370 3505);
FORCEADD RES..2
(-900 3825);
FORCEPROP 1 LAST PACK_TYPE 0402
J 0
(-860 3650);
DISPLAY 0.617021 (-860 3650);
PAINT SKYBLUE (-860 3650);
FORCEPROP 1 LASTPIN (-900 3725) $PN 2
J 0
(-895 3735);
DISPLAY 0.617021 (-895 3735);
PAINT ORANGE (-895 3735);
FORCEPROP 1 LASTPIN (-900 3925) $PN 1
J 0
(-895 3887);
DISPLAY 0.617021 (-895 3887);
PAINT ORANGE (-895 3887);
FORCEPROP 1 LAST TOLERANCE 1%
J 0
(-855 3850);
DISPLAY 0.617021 (-855 3850);
PAINT SKYBLUE (-855 3850);
FORCEPROP 1 LAST WATTAGE 1/16W
J 0
(-860 3800);
DISPLAY 0.617021 (-860 3800);
PAINT SKYBLUE (-860 3800);
FORCEPROP 1 LAST MATERIAL CHIP
J 0
(-860 3750);
DISPLAY 0.617021 (-860 3750);
PAINT SKYBLUE (-860 3750);
FORCEPROP 1 LAST PART_NUMBER G21796-027
J 0
(-860 3700);
DISPLAY 0.617021 (-860 3700);
PAINT BLUE (-860 3700);
FORCEPROP 1 LAST VALUE 3.32K
J 0
(-855 3900);
DISPLAY 0.617021 (-855 3900);
PAINT SKYBLUE (-855 3900);
FORCEPROP 1 LAST LOCATION R9F5
J 0
(-855 3950);
DISPLAY 0.617021 (-855 3950);
PAINT AQUA (-855 3950);
FORCEPROP 0 LAST GROUP NI_I210&RJ45
J 0
(-894 3538);
DISPLAY 0.638298 (-894 3538);
PAINT BROWN (-894 3538);
DISPLAY BOTH (-894 3538);
FORCEPROP 2 LAST CDS_LIB mstr_discrete
J 0
(-900 3825);
PAINT ORANGE (-900 3825);
DISPLAY INVISIBLE (-900 3825);
FORCEPROP 2 LAST ROOM NIC_SPRV
J 0
(-850 4000);
DISPLAY 1.021277 (-850 4000);
PAINT ORANGE (-850 4000);
DISPLAY INVISIBLE (-850 4000);
FORCEPROP 1 LAST PATH I173
J 0
(-850 4000);
DISPLAY 0.978723 (-850 4000);
PAINT WHITE (-850 4000);
DISPLAY INVISIBLE (-850 4000);
FORCEPROP 2 LAST CDS_LOCATION R9F5
J 0
(-855 3950);
DISPLAY 0.617021 (-855 3950);
PAINT AQUA (-855 3950);
DISPLAY INVISIBLE (-855 3950);
FORCEPROP 2 LAST $SEC 1
J 0
(-850 4050);
PAINT MONO (-850 4050);
DISPLAY INVISIBLE (-850 4050);
FORCEPROP 2 LAST BOM_COST NT_GBE_BASE
J 0
(-850 4050);
DISPLAY 1.021277 (-850 4050);
PAINT ORANGE (-850 4050);
DISPLAY INVISIBLE (-850 4050);
FORCEPROP 2 LAST CDS_SEC 1
J 0
(-850 4050);
PAINT MONO (-850 4050);
DISPLAY INVISIBLE (-850 4050);
FORCEADD RES..2
(-900 3225);
FORCEPROP 1 LAST PART_NUMBER G21796-013
J 0
(-860 3100);
DISPLAY 0.617021 (-860 3100);
PAINT BLUE (-860 3100);
FORCEPROP 1 LAST PACK_TYPE 0402
J 0
(-860 3050);
DISPLAY 0.617021 (-860 3050);
PAINT SKYBLUE (-860 3050);
FORCEPROP 0 LAST GROUP NI_I210&RJ45
J 0
(-869 3013);
DISPLAY 0.638298 (-869 3013);
PAINT BROWN (-869 3013);
DISPLAY BOTH (-869 3013);
FORCEPROP 1 LAST MATERIAL CHIP
J 0
(-860 3150);
DISPLAY 0.617021 (-860 3150);
PAINT SKYBLUE (-860 3150);
FORCEPROP 1 LASTPIN (-900 3125) $PN 2
J 0
(-895 3135);
DISPLAY 0.617021 (-895 3135);
PAINT ORANGE (-895 3135);
FORCEPROP 1 LAST TOLERANCE 1%
J 0
(-855 3250);
DISPLAY 0.617021 (-855 3250);
PAINT SKYBLUE (-855 3250);
FORCEPROP 1 LAST WATTAGE 1/16W
J 0
(-860 3200);
DISPLAY 0.617021 (-860 3200);
PAINT SKYBLUE (-860 3200);
FORCEPROP 1 LASTPIN (-900 3325) $PN 1
J 0
(-895 3287);
DISPLAY 0.617021 (-895 3287);
PAINT ORANGE (-895 3287);
FORCEPROP 1 LAST VALUE 4.99K
J 0
(-855 3300);
DISPLAY 0.617021 (-855 3300);
PAINT SKYBLUE (-855 3300);
FORCEPROP 1 LAST LOCATION R9E23
J 0
(-855 3350);
DISPLAY 0.617021 (-855 3350);
PAINT AQUA (-855 3350);
FORCEPROP 2 LAST CDS_LIB mstr_discrete
J 0
(-900 3225);
PAINT ORANGE (-900 3225);
DISPLAY INVISIBLE (-900 3225);
FORCEPROP 2 LAST ROOM NIC_SPRV
J 0
(-850 3400);
DISPLAY 1.021277 (-850 3400);
PAINT ORANGE (-850 3400);
DISPLAY INVISIBLE (-850 3400);
FORCEPROP 1 LAST PATH I174
J 0
(-850 3400);
DISPLAY 0.978723 (-850 3400);
PAINT WHITE (-850 3400);
DISPLAY INVISIBLE (-850 3400);
FORCEPROP 2 LAST CDS_LOCATION R9E23
J 0
(-855 3350);
DISPLAY 0.617021 (-855 3350);
PAINT AQUA (-855 3350);
DISPLAY INVISIBLE (-855 3350);
FORCEPROP 2 LAST SEC_TYPE 0402
J 0
(-850 3450);
DISPLAY 1.021277 (-850 3450);
PAINT ORANGE (-850 3450);
DISPLAY INVISIBLE (-850 3450);
FORCEPROP 2 LAST BOM_COST NT_GBE_BASE
J 0
(-850 3450);
DISPLAY 1.021277 (-850 3450);
PAINT ORANGE (-850 3450);
DISPLAY INVISIBLE (-850 3450);
FORCEPROP 2 LAST SEC 1
J 0
(-850 3450);
DISPLAY 0.680851 (-850 3450);
PAINT MONO (-850 3450);
DISPLAY INVISIBLE (-850 3450);
FORCEADD OFFPAGE..2
(-375 3400);
FORCEPROP 2 LAST $XR0 139 
J 0
(-186 3400);
DISPLAY 0.638298 (-186 3400);
PAINT MONO (-186 3400);
FORCEPROP 1 LAST COMMENT_BODY TRUE
J 0
(-420 3305);
DISPLAY 0.872340 (-420 3305);
PAINT GREEN (-420 3305);
DISPLAY INVISIBLE (-420 3305);
FORCEPROP 1 LAST OFFPAGE TRUE
J 0
(-50 3275);
DISPLAY 0.872340 (-50 3275);
PAINT GREEN (-50 3275);
DISPLAY INVISIBLE (-50 3275);
FORCEPROP 2 LAST PATH I175
J 0
(-200 3475);
DISPLAY 1.021277 (-200 3475);
PAINT ORANGE (-200 3475);
DISPLAY INVISIBLE (-200 3475);
FORCEPROP 2 LAST CDS_LIB mstr_standard
J 0
(-375 3400);
PAINT ORANGE (-375 3400);
DISPLAY INVISIBLE (-375 3400);
FORCEADD GND..1
(-900 2950);
FORCEPROP 3 LASTPIN (-900 3000) SIG_NAME GND\g
J 0
(-890 3010);
DISPLAY 0.659574 (-890 3010);
PAINT MONO (-890 3010);
DISPLAY INVISIBLE (-890 3010);
FORCEPROP 1 LAST PATH I176
J 0
(-825 2950);
DISPLAY 0.872340 (-825 2950);
PAINT AQUA (-825 2950);
DISPLAY INVISIBLE (-825 2950);
FORCEPROP 1 LAST SIZE 1B
J 0
(-825 2900);
DISPLAY 0.872340 (-825 2900);
PAINT AQUA (-825 2900);
DISPLAY INVISIBLE (-825 2900);
FORCEPROP 2 LAST CDS_LIB mstr_symbols
J 0
(-900 2950);
PAINT ORANGE (-900 2950);
DISPLAY INVISIBLE (-900 2950);
FORCEPROP 1 LAST VOLTAGE 0.0V
J 0
(-945 2907);
DISPLAY 0.340426 (-945 2907);
PAINT SKYBLUE (-945 2907);
DISPLAY INVISIBLE (-945 2907);
FORCEPROP 1 LAST BODY_TYPE PLUMBING
J 0
(-945 2907);
DISPLAY 0.340426 (-945 2907);
PAINT GREEN (-945 2907);
DISPLAY INVISIBLE (-945 2907);
FORCEPROP 1 LAST HDL_POWER GND
J 0
(-900 3100);
DISPLAY 0.872340 (-900 3100);
PAINT GREEN (-900 3100);
DISPLAY INVISIBLE (-900 3100);
FORCEADD RES..2
(-7200 3125);
FORCEPROP 0 LAST GROUP NI_I210&RJ45
J 0
(-7019 2938);
DISPLAY 0.638298 (-7019 2938);
PAINT BROWN (-7019 2938);
DISPLAY BOTH (-7019 2938);
FORCEPROP 1 LAST VALUE 10.0K
J 0
(-7155 3200);
DISPLAY 0.617021 (-7155 3200);
PAINT SKYBLUE (-7155 3200);
FORCEPROP 1 LAST LOCATION R9E2
J 0
(-7155 3250);
DISPLAY 0.617021 (-7155 3250);
PAINT AQUA (-7155 3250);
FORCEPROP 1 LASTPIN (-7200 3225) $PN 1
J 0
(-7195 3187);
DISPLAY 0.617021 (-7195 3187);
PAINT ORANGE (-7195 3187);
FORCEPROP 1 LASTPIN (-7200 3025) $PN 2
J 0
(-7195 3035);
DISPLAY 0.617021 (-7195 3035);
PAINT ORANGE (-7195 3035);
FORCEPROP 1 LAST MATERIAL CHIP
J 0
(-7160 3050);
DISPLAY 0.617021 (-7160 3050);
PAINT SKYBLUE (-7160 3050);
FORCEPROP 1 LAST WATTAGE 1/16W
J 0
(-7160 3100);
DISPLAY 0.617021 (-7160 3100);
PAINT SKYBLUE (-7160 3100);
FORCEPROP 1 LAST PACK_TYPE 0402
J 0
(-7160 2950);
DISPLAY 0.617021 (-7160 2950);
PAINT SKYBLUE (-7160 2950);
FORCEPROP 1 LAST PART_NUMBER G21796-016
J 0
(-7160 3000);
DISPLAY 0.617021 (-7160 3000);
PAINT BLUE (-7160 3000);
FORCEPROP 1 LAST TOLERANCE 1%
J 0
(-7155 3150);
DISPLAY 0.617021 (-7155 3150);
PAINT SKYBLUE (-7155 3150);
FORCEPROP 2 LAST CDS_LIB mstr_discrete
J 0
(-7200 3125);
PAINT ORANGE (-7200 3125);
DISPLAY INVISIBLE (-7200 3125);
FORCEPROP 2 LAST CDS_LOCATION R9E2
J 0
(-7155 3250);
DISPLAY 0.617021 (-7155 3250);
PAINT AQUA (-7155 3250);
DISPLAY INVISIBLE (-7155 3250);
FORCEPROP 2 LAST ROOM NIC_SPRV
J 0
(-7150 3300);
DISPLAY 1.021277 (-7150 3300);
PAINT ORANGE (-7150 3300);
DISPLAY INVISIBLE (-7150 3300);
FORCEPROP 2 LAST SEC 1
J 0
(-7150 3350);
DISPLAY 0.680851 (-7150 3350);
PAINT MONO (-7150 3350);
DISPLAY INVISIBLE (-7150 3350);
FORCEPROP 2 LAST SEC_TYPE 0402
J 0
(-7150 3350);
DISPLAY 1.021277 (-7150 3350);
PAINT ORANGE (-7150 3350);
DISPLAY INVISIBLE (-7150 3350);
FORCEPROP 2 LAST BOM_COST NT_GBE_BASE
J 0
(-7150 3350);
DISPLAY 1.021277 (-7150 3350);
PAINT ORANGE (-7150 3350);
DISPLAY INVISIBLE (-7150 3350);
FORCEPROP 1 LAST PATH I177
J 0
(-7150 3300);
DISPLAY 0.978723 (-7150 3300);
PAINT WHITE (-7150 3300);
DISPLAY INVISIBLE (-7150 3300);
FORCEADD RES..2
(-7475 3125);
FORCEPROP 1 LAST LOCATION R9E3
J 0
(-7430 3250);
DISPLAY 0.617021 (-7430 3250);
PAINT AQUA (-7430 3250);
FORCEPROP 1 LAST VALUE 10.0K
J 0
(-7430 3200);
DISPLAY 0.617021 (-7430 3200);
PAINT SKYBLUE (-7430 3200);
FORCEPROP 1 LAST WATTAGE 1/16W
J 0
(-7435 3100);
DISPLAY 0.617021 (-7435 3100);
PAINT SKYBLUE (-7435 3100);
FORCEPROP 1 LASTPIN (-7475 3225) $PN 1
J 0
(-7470 3187);
DISPLAY 0.617021 (-7470 3187);
PAINT ORANGE (-7470 3187);
FORCEPROP 1 LAST PACK_TYPE 0402
J 0
(-7435 2950);
DISPLAY 0.617021 (-7435 2950);
PAINT SKYBLUE (-7435 2950);
FORCEPROP 1 LAST TOLERANCE 1%
J 0
(-7430 3150);
DISPLAY 0.617021 (-7430 3150);
PAINT SKYBLUE (-7430 3150);
FORCEPROP 1 LASTPIN (-7475 3025) $PN 2
J 0
(-7470 3035);
DISPLAY 0.617021 (-7470 3035);
PAINT ORANGE (-7470 3035);
FORCEPROP 1 LAST MATERIAL CHIP
J 0
(-7435 3050);
DISPLAY 0.617021 (-7435 3050);
PAINT SKYBLUE (-7435 3050);
FORCEPROP 1 LAST PART_NUMBER G21796-016
J 0
(-7435 3000);
DISPLAY 0.617021 (-7435 3000);
PAINT BLUE (-7435 3000);
FORCEPROP 0 LAST GROUP NI_I210&RJ45
J 0
(-7419 2888);
DISPLAY 0.638298 (-7419 2888);
PAINT BROWN (-7419 2888);
DISPLAY BOTH (-7419 2888);
FORCEPROP 2 LAST CDS_LIB mstr_discrete
J 0
(-7475 3125);
PAINT ORANGE (-7475 3125);
DISPLAY INVISIBLE (-7475 3125);
FORCEPROP 2 LAST CDS_LOCATION R9E3
J 0
(-7430 3250);
DISPLAY 0.617021 (-7430 3250);
PAINT AQUA (-7430 3250);
DISPLAY INVISIBLE (-7430 3250);
FORCEPROP 2 LAST ROOM NIC_SPRV
J 0
(-7425 3300);
DISPLAY 1.021277 (-7425 3300);
PAINT ORANGE (-7425 3300);
DISPLAY INVISIBLE (-7425 3300);
FORCEPROP 1 LAST PATH I178
J 0
(-7425 3300);
DISPLAY 0.978723 (-7425 3300);
PAINT WHITE (-7425 3300);
DISPLAY INVISIBLE (-7425 3300);
FORCEPROP 2 LAST SEC 1
J 0
(-7425 3350);
DISPLAY 0.680851 (-7425 3350);
PAINT MONO (-7425 3350);
DISPLAY INVISIBLE (-7425 3350);
FORCEPROP 2 LAST SEC_TYPE 0402
J 0
(-7425 3350);
DISPLAY 1.021277 (-7425 3350);
PAINT ORANGE (-7425 3350);
DISPLAY INVISIBLE (-7425 3350);
FORCEPROP 2 LAST BOM_COST NT_GBE_BASE
J 0
(-7425 3350);
DISPLAY 1.021277 (-7425 3350);
PAINT ORANGE (-7425 3350);
DISPLAY INVISIBLE (-7425 3350);
FORCEADD RES..2
(-7750 3125);
FORCEPROP 1 LAST PART_NUMBER G21796-016
J 0
(-7710 3000);
DISPLAY 0.617021 (-7710 3000);
PAINT BLUE (-7710 3000);
FORCEPROP 1 LAST LOCATION R9E1
J 0
(-7705 3250);
DISPLAY 0.617021 (-7705 3250);
PAINT AQUA (-7705 3250);
FORCEPROP 1 LAST VALUE 10.0K
J 0
(-7705 3200);
DISPLAY 0.617021 (-7705 3200);
PAINT SKYBLUE (-7705 3200);
FORCEPROP 1 LAST TOLERANCE 1%
J 0
(-7705 3150);
DISPLAY 0.617021 (-7705 3150);
PAINT SKYBLUE (-7705 3150);
FORCEPROP 1 LASTPIN (-7750 3225) $PN 1
J 0
(-7745 3187);
DISPLAY 0.617021 (-7745 3187);
PAINT ORANGE (-7745 3187);
FORCEPROP 1 LAST WATTAGE 1/16W
J 0
(-7710 3100);
DISPLAY 0.617021 (-7710 3100);
PAINT SKYBLUE (-7710 3100);
FORCEPROP 1 LAST MATERIAL CHIP
J 0
(-7710 3050);
DISPLAY 0.617021 (-7710 3050);
PAINT SKYBLUE (-7710 3050);
FORCEPROP 1 LASTPIN (-7750 3025) $PN 2
J 0
(-7745 3035);
DISPLAY 0.617021 (-7745 3035);
PAINT ORANGE (-7745 3035);
FORCEPROP 0 LAST GROUP NI_I210&RJ45
J 0
(-7719 2838);
DISPLAY 0.638298 (-7719 2838);
PAINT BROWN (-7719 2838);
DISPLAY BOTH (-7719 2838);
FORCEPROP 1 LAST PACK_TYPE 0402
J 0
(-7710 2950);
DISPLAY 0.617021 (-7710 2950);
PAINT SKYBLUE (-7710 2950);
FORCEPROP 2 LAST SEC_TYPE 0402
J 0
(-7700 3350);
DISPLAY 1.021277 (-7700 3350);
PAINT ORANGE (-7700 3350);
DISPLAY INVISIBLE (-7700 3350);
FORCEPROP 2 LAST BOM_COST NT_GBE_BASE
J 0
(-7700 3350);
DISPLAY 1.021277 (-7700 3350);
PAINT ORANGE (-7700 3350);
DISPLAY INVISIBLE (-7700 3350);
FORCEPROP 2 LAST SEC 1
J 0
(-7700 3350);
DISPLAY 0.680851 (-7700 3350);
PAINT MONO (-7700 3350);
DISPLAY INVISIBLE (-7700 3350);
FORCEPROP 1 LAST PATH I179
J 0
(-7700 3300);
DISPLAY 0.978723 (-7700 3300);
PAINT WHITE (-7700 3300);
DISPLAY INVISIBLE (-7700 3300);
FORCEPROP 2 LAST ROOM NIC_SPRV
J 0
(-7700 3300);
DISPLAY 1.021277 (-7700 3300);
PAINT ORANGE (-7700 3300);
DISPLAY INVISIBLE (-7700 3300);
FORCEPROP 2 LAST CDS_LOCATION R9E1
J 0
(-7705 3250);
DISPLAY 0.617021 (-7705 3250);
PAINT AQUA (-7705 3250);
DISPLAY INVISIBLE (-7705 3250);
FORCEPROP 2 LAST CDS_LIB mstr_discrete
J 0
(-7750 3125);
PAINT ORANGE (-7750 3125);
DISPLAY INVISIBLE (-7750 3125);
FORCEADD P3V3_STBY..1
(-7750 3550);
FORCEPROP 3 LASTPIN (-7750 3500) SIG_NAME P3V3_STBY\g
J 0
(-7740 3510);
DISPLAY 0.659574 (-7740 3510);
PAINT MONO (-7740 3510);
DISPLAY INVISIBLE (-7740 3510);
FORCEPROP 1 LAST PATH I180
J 0
(-7705 3552);
DISPLAY 0.340426 (-7705 3552);
PAINT GREEN (-7705 3552);
DISPLAY INVISIBLE (-7705 3552);
FORCEPROP 2 LAST CDS_LIB mstr_symbols
J 0
(-7750 3550);
PAINT ORANGE (-7750 3550);
DISPLAY INVISIBLE (-7750 3550);
FORCEPROP 1 LAST SIZE 1B
J 0
(-7705 3572);
DISPLAY 0.340426 (-7705 3572);
PAINT GREEN (-7705 3572);
DISPLAY INVISIBLE (-7705 3572);
FORCEPROP 1 LAST VOLTAGE 3.3V
J 0
(-7795 3507);
DISPLAY 0.340426 (-7795 3507);
PAINT SKYBLUE (-7795 3507);
DISPLAY INVISIBLE (-7795 3507);
FORCEPROP 1 LAST BODY_TYPE PLUMBING
J 0
(-7795 3507);
DISPLAY 0.340426 (-7795 3507);
PAINT GREEN (-7795 3507);
DISPLAY INVISIBLE (-7795 3507);
FORCEPROP 1 LAST HDL_POWER P3V3_STBY
J 0
(-8050 3425);
DISPLAY 0.872340 (-8050 3425);
PAINT ORANGE (-8050 3425);
DISPLAY INVISIBLE (-8050 3425);
FORCEADD RES..1
(-1500 2825);
FORCEPROP 1 LAST WATTAGE 1/16W
J 2
(-1000 2825);
DISPLAY 0.617021 (-1000 2825);
PAINT SKYBLUE (-1000 2825);
FORCEPROP 1 LAST LOCATION R9E22
J 0
(-1350 2825);
DISPLAY 0.617021 (-1350 2825);
PAINT AQUA (-1350 2825);
FORCEPROP 1 LAST MATERIAL CHIP
J 0
(-1450 2775);
DISPLAY 0.617021 (-1450 2775);
PAINT SKYBLUE (-1450 2775);
FORCEPROP 1 LAST VALUE 10.0K
J 2
(-1550 2900);
DISPLAY 0.617021 (-1550 2900);
PAINT SKYBLUE (-1550 2900);
FORCEPROP 1 LAST PACK_TYPE 0402
J 0
(-1300 2775);
DISPLAY 0.617021 (-1300 2775);
PAINT SKYBLUE (-1300 2775);
FORCEPROP 1 LASTPIN (-1400 2825) $PN 2
J 0
(-1438 2837);
DISPLAY 0.617021 (-1438 2837);
PAINT ORANGE (-1438 2837);
FORCEPROP 1 LASTPIN (-1600 2825) $PN 1
J 0
(-1588 2837);
DISPLAY 0.617021 (-1588 2837);
PAINT ORANGE (-1588 2837);
FORCEPROP 1 LAST TOLERANCE 1%
J 0
(-1525 2900);
DISPLAY 0.617021 (-1525 2900);
PAINT SKYBLUE (-1525 2900);
FORCEPROP 1 LAST PART_NUMBER G21796-016
J 0
(-1850 2825);
DISPLAY 0.617021 (-1850 2825);
PAINT BLUE (-1850 2825);
FORCEPROP 0 LAST GROUP NI_I210&RJ45
J 0
(-1169 2763);
DISPLAY 0.638298 (-1169 2763);
PAINT BROWN (-1169 2763);
DISPLAY BOTH (-1169 2763);
FORCEPROP 2 LAST ROOM NIC_SPRV
J 0
(-1550 2925);
DISPLAY 1.021277 (-1550 2925);
PAINT ORANGE (-1550 2925);
DISPLAY INVISIBLE (-1550 2925);
FORCEPROP 1 LAST PATH I181
J 0
(-1550 2975);
DISPLAY 0.978723 (-1550 2975);
PAINT WHITE (-1550 2975);
DISPLAY INVISIBLE (-1550 2975);
FORCEPROP 2 LAST SEC 1
J 0
(-1550 3025);
DISPLAY 0.680851 (-1550 3025);
PAINT MONO (-1550 3025);
DISPLAY INVISIBLE (-1550 3025);
FORCEPROP 2 LAST BOM_COST NT_GBE_BASE
J 0
(-1550 2975);
DISPLAY 1.021277 (-1550 2975);
PAINT ORANGE (-1550 2975);
DISPLAY INVISIBLE (-1550 2975);
FORCEPROP 2 LAST SEC_TYPE 0402
J 0
(-1550 3025);
DISPLAY 1.021277 (-1550 3025);
PAINT ORANGE (-1550 3025);
DISPLAY INVISIBLE (-1550 3025);
FORCEPROP 2 LAST CDS_LIB mstr_discrete
J 0
(-1500 2825);
PAINT ORANGE (-1500 2825);
DISPLAY INVISIBLE (-1500 2825);
FORCEPROP 2 LAST CDS_LOCATION R9E22
J 0
(-1350 2825);
DISPLAY 0.617021 (-1350 2825);
PAINT AQUA (-1350 2825);
DISPLAY INVISIBLE (-1350 2825);
FORCEADD P3V3_STBY..1
(-1175 3200);
FORCEPROP 3 LASTPIN (-1175 3150) SIG_NAME P3V3_STBY\g
J 0
(-1165 3160);
DISPLAY 0.659574 (-1165 3160);
PAINT MONO (-1165 3160);
DISPLAY INVISIBLE (-1165 3160);
FORCEPROP 1 LAST PATH I182
J 0
(-1130 3202);
DISPLAY 0.340426 (-1130 3202);
PAINT GREEN (-1130 3202);
DISPLAY INVISIBLE (-1130 3202);
FORCEPROP 2 LAST CDS_LIB mstr_symbols
J 0
(-1175 3200);
PAINT ORANGE (-1175 3200);
DISPLAY INVISIBLE (-1175 3200);
FORCEPROP 1 LAST SIZE 1B
J 0
(-1130 3222);
DISPLAY 0.340426 (-1130 3222);
PAINT GREEN (-1130 3222);
DISPLAY INVISIBLE (-1130 3222);
FORCEPROP 1 LAST VOLTAGE 3.3V
J 0
(-1220 3157);
DISPLAY 0.340426 (-1220 3157);
PAINT SKYBLUE (-1220 3157);
DISPLAY INVISIBLE (-1220 3157);
FORCEPROP 1 LAST BODY_TYPE PLUMBING
J 0
(-1220 3157);
DISPLAY 0.340426 (-1220 3157);
PAINT GREEN (-1220 3157);
DISPLAY INVISIBLE (-1220 3157);
FORCEPROP 1 LAST HDL_POWER P3V3_STBY
J 0
(-1475 3075);
DISPLAY 0.872340 (-1475 3075);
PAINT ORANGE (-1475 3075);
DISPLAY INVISIBLE (-1475 3075);
FORCEADD OFFPAGE..2
(-2600 3825);
FORCEPROP 2 LAST $XR0 141 
J 0
(-2411 3825);
DISPLAY 0.638298 (-2411 3825);
PAINT MONO (-2411 3825);
FORCEPROP 2 LAST CDS_LIB mstr_standard
J 0
(-2600 3825);
PAINT ORANGE (-2600 3825);
DISPLAY INVISIBLE (-2600 3825);
FORCEPROP 2 LAST PATH I183
J 0
(-2550 3900);
DISPLAY 1.021277 (-2550 3900);
PAINT ORANGE (-2550 3900);
DISPLAY INVISIBLE (-2550 3900);
FORCEPROP 1 LAST OFFPAGE TRUE
J 0
(-2275 3700);
DISPLAY 0.872340 (-2275 3700);
PAINT GREEN (-2275 3700);
DISPLAY INVISIBLE (-2275 3700);
FORCEPROP 1 LAST COMMENT_BODY TRUE
J 0
(-2645 3730);
DISPLAY 0.872340 (-2645 3730);
PAINT GREEN (-2645 3730);
DISPLAY INVISIBLE (-2645 3730);
FORCEADD OFFPAGE..2
(-2600 3775);
FORCEPROP 2 LAST $XR0 141 
J 0
(-2411 3775);
DISPLAY 0.638298 (-2411 3775);
PAINT MONO (-2411 3775);
FORCEPROP 2 LAST CDS_LIB mstr_standard
J 0
(-2600 3775);
PAINT ORANGE (-2600 3775);
DISPLAY INVISIBLE (-2600 3775);
FORCEPROP 2 LAST PATH I184
J 0
(-2425 3850);
DISPLAY 1.021277 (-2425 3850);
PAINT ORANGE (-2425 3850);
DISPLAY INVISIBLE (-2425 3850);
FORCEPROP 1 LAST OFFPAGE TRUE
J 0
(-2275 3650);
DISPLAY 0.872340 (-2275 3650);
PAINT GREEN (-2275 3650);
DISPLAY INVISIBLE (-2275 3650);
FORCEPROP 1 LAST COMMENT_BODY TRUE
J 0
(-2645 3680);
DISPLAY 0.872340 (-2645 3680);
PAINT GREEN (-2645 3680);
DISPLAY INVISIBLE (-2645 3680);
FORCEADD OFFPAGE..2
(-2600 3725);
FORCEPROP 2 LAST $XR0 141 
J 0
(-2411 3725);
DISPLAY 0.638298 (-2411 3725);
PAINT MONO (-2411 3725);
FORCEPROP 2 LAST CDS_LIB mstr_standard
J 0
(-2600 3725);
PAINT ORANGE (-2600 3725);
DISPLAY INVISIBLE (-2600 3725);
FORCEPROP 2 LAST PATH I185
J 0
(-2425 3800);
DISPLAY 1.021277 (-2425 3800);
PAINT ORANGE (-2425 3800);
DISPLAY INVISIBLE (-2425 3800);
FORCEPROP 1 LAST OFFPAGE TRUE
J 0
(-2275 3600);
DISPLAY 0.872340 (-2275 3600);
PAINT GREEN (-2275 3600);
DISPLAY INVISIBLE (-2275 3600);
FORCEPROP 1 LAST COMMENT_BODY TRUE
J 0
(-2645 3630);
DISPLAY 0.872340 (-2645 3630);
PAINT GREEN (-2645 3630);
DISPLAY INVISIBLE (-2645 3630);
FORCEADD P3V3_STBY..1
(-6950 4000);
FORCEPROP 3 LASTPIN (-6950 3950) SIG_NAME P3V3_STBY\g
J 0
(-6940 3960);
DISPLAY 0.659574 (-6940 3960);
PAINT MONO (-6940 3960);
DISPLAY INVISIBLE (-6940 3960);
FORCEPROP 1 LAST VOLTAGE 3.3V
J 0
(-6995 3957);
DISPLAY 0.340426 (-6995 3957);
PAINT SKYBLUE (-6995 3957);
DISPLAY INVISIBLE (-6995 3957);
FORCEPROP 1 LAST PATH I186
J 0
(-6905 4002);
DISPLAY 0.340426 (-6905 4002);
PAINT GREEN (-6905 4002);
DISPLAY INVISIBLE (-6905 4002);
FORCEPROP 1 LAST SIZE 1B
J 0
(-6905 4022);
DISPLAY 0.340426 (-6905 4022);
PAINT GREEN (-6905 4022);
DISPLAY INVISIBLE (-6905 4022);
FORCEPROP 2 LAST CDS_LIB mstr_symbols
J 0
(-6950 4000);
PAINT ORANGE (-6950 4000);
DISPLAY INVISIBLE (-6950 4000);
FORCEPROP 1 LAST BODY_TYPE PLUMBING
J 0
(-6995 3957);
DISPLAY 0.340426 (-6995 3957);
PAINT GREEN (-6995 3957);
DISPLAY INVISIBLE (-6995 3957);
FORCEPROP 1 LAST HDL_POWER P3V3_STBY
J 0
(-7250 3875);
DISPLAY 0.872340 (-7250 3875);
PAINT ORANGE (-7250 3875);
DISPLAY INVISIBLE (-7250 3875);
FORCEADD P3V3_STBY..1
(-900 4050);
FORCEPROP 3 LASTPIN (-900 4000) SIG_NAME P3V3_STBY\g
J 0
(-890 4010);
DISPLAY 0.659574 (-890 4010);
PAINT MONO (-890 4010);
DISPLAY INVISIBLE (-890 4010);
FORCEPROP 1 LAST VOLTAGE 3.3V
J 0
(-945 4007);
DISPLAY 0.340426 (-945 4007);
PAINT SKYBLUE (-945 4007);
DISPLAY INVISIBLE (-945 4007);
FORCEPROP 2 LAST CDS_LIB mstr_symbols
J 0
(-900 4050);
PAINT ORANGE (-900 4050);
DISPLAY INVISIBLE (-900 4050);
FORCEPROP 1 LAST SIZE 1B
J 0
(-855 4072);
DISPLAY 0.340426 (-855 4072);
PAINT GREEN (-855 4072);
DISPLAY INVISIBLE (-855 4072);
FORCEPROP 1 LAST PATH I188
J 0
(-855 4052);
DISPLAY 0.340426 (-855 4052);
PAINT GREEN (-855 4052);
DISPLAY INVISIBLE (-855 4052);
FORCEPROP 1 LAST BODY_TYPE PLUMBING
J 0
(-945 4007);
DISPLAY 0.340426 (-945 4007);
PAINT GREEN (-945 4007);
DISPLAY INVISIBLE (-945 4007);
FORCEPROP 1 LAST HDL_POWER P3V3_STBY
J 0
(-1200 3925);
DISPLAY 0.872340 (-1200 3925);
PAINT ORANGE (-1200 3925);
DISPLAY INVISIBLE (-1200 3925);
FORCEADD P3V3_STBY..1
(-6200 1200);
FORCEPROP 3 LASTPIN (-6200 1150) SIG_NAME P3V3_STBY\g
J 0
(-6190 1160);
DISPLAY 0.659574 (-6190 1160);
PAINT MONO (-6190 1160);
DISPLAY INVISIBLE (-6190 1160);
FORCEPROP 1 LAST HDL_POWER P3V3_STBY
J 0
(-6500 1075);
DISPLAY 0.872340 (-6500 1075);
PAINT ORANGE (-6500 1075);
DISPLAY INVISIBLE (-6500 1075);
FORCEPROP 1 LAST BODY_TYPE PLUMBING
J 0
(-6245 1157);
DISPLAY 0.340426 (-6245 1157);
PAINT GREEN (-6245 1157);
DISPLAY INVISIBLE (-6245 1157);
FORCEPROP 1 LAST SIZE 1B
J 0
(-6155 1222);
DISPLAY 0.340426 (-6155 1222);
PAINT GREEN (-6155 1222);
DISPLAY INVISIBLE (-6155 1222);
FORCEPROP 1 LAST PATH I189
J 0
(-6155 1202);
DISPLAY 0.340426 (-6155 1202);
PAINT GREEN (-6155 1202);
DISPLAY INVISIBLE (-6155 1202);
FORCEPROP 1 LAST VOLTAGE 3.3V
J 0
(-6245 1157);
DISPLAY 0.340426 (-6245 1157);
PAINT SKYBLUE (-6245 1157);
DISPLAY INVISIBLE (-6245 1157);
FORCEPROP 2 LAST CDS_LIB mstr_symbols
J 0
(-6200 1200);
PAINT ORANGE (-6200 1200);
DISPLAY INVISIBLE (-6200 1200);
FORCEADD OFFPAGE..5
(-6900 2225);
FORCEPROP 2 LAST $XR0 142 
J 0
(-7155 2225);
DISPLAY 0.638298 (-7155 2225);
PAINT MONO (-7155 2225);
FORCEPROP 1 LAST COMMENT_BODY TRUE
J 0
(-6800 2150);
DISPLAY 0.872340 (-6800 2150);
PAINT GREEN (-6800 2150);
DISPLAY INVISIBLE (-6800 2150);
FORCEPROP 1 LAST OFFPAGE TRUE
J 0
(-6575 2100);
DISPLAY 0.872340 (-6575 2100);
PAINT GREEN (-6575 2100);
DISPLAY INVISIBLE (-6575 2100);
FORCEPROP 2 LAST PATH I191
J 0
(-6850 2300);
DISPLAY 1.021277 (-6850 2300);
PAINT ORANGE (-6850 2300);
DISPLAY INVISIBLE (-6850 2300);
FORCEPROP 2 LAST CDS_LIB mstr_standard
J 0
(-6900 2225);
PAINT ORANGE (-6900 2225);
DISPLAY INVISIBLE (-6900 2225);
FORCEADD OFFPAGE..2
(-425 4250);
FORCEPROP 2 LAST $XR2 146 
J 0
(-236 4214);
DISPLAY 0.638298 (-236 4214);
PAINT MONO (-236 4214);
FORCEPROP 2 LAST $XR1 119 
J 0
(-116 4250);
DISPLAY 0.638298 (-116 4250);
PAINT MONO (-116 4250);
FORCEPROP 2 LAST $XR0 139 
J 0
(-236 4250);
DISPLAY 0.638298 (-236 4250);
PAINT MONO (-236 4250);
FORCEPROP 2 LAST CDS_LIB mstr_standard
J 0
(-425 4250);
PAINT ORANGE (-425 4250);
DISPLAY INVISIBLE (-425 4250);
FORCEPROP 2 LAST PATH I192
J 0
(-225 4300);
DISPLAY 1.021277 (-225 4300);
PAINT ORANGE (-225 4300);
DISPLAY INVISIBLE (-225 4300);
FORCEPROP 1 LAST OFFPAGE TRUE
J 0
(-100 4125);
DISPLAY 0.872340 (-100 4125);
PAINT GREEN (-100 4125);
DISPLAY INVISIBLE (-100 4125);
FORCEPROP 1 LAST COMMENT_BODY TRUE
J 0
(-470 4155);
DISPLAY 0.872340 (-470 4155);
PAINT GREEN (-470 4155);
DISPLAY INVISIBLE (-470 4155);
FORCEADD RES..2
(-1000 4475);
FORCEPROP 1 LASTPIN (-1000 4575) $PN 1
J 0
(-995 4537);
DISPLAY 0.617021 (-995 4537);
PAINT ORANGE (-995 4537);
FORCEPROP 1 LAST PACK_TYPE 0402
J 0
(-960 4300);
DISPLAY 0.617021 (-960 4300);
PAINT SKYBLUE (-960 4300);
FORCEPROP 1 LAST VALUE 3.32K
J 0
(-955 4550);
DISPLAY 0.617021 (-955 4550);
PAINT SKYBLUE (-955 4550);
FORCEPROP 1 LAST MATERIAL CHIP
J 0
(-960 4400);
DISPLAY 0.617021 (-960 4400);
PAINT SKYBLUE (-960 4400);
FORCEPROP 1 LAST LOCATION R9E7
J 0
(-955 4600);
DISPLAY 0.617021 (-955 4600);
PAINT AQUA (-955 4600);
FORCEPROP 1 LAST TOLERANCE 1%
J 0
(-955 4500);
DISPLAY 0.617021 (-955 4500);
PAINT SKYBLUE (-955 4500);
FORCEPROP 1 LAST WATTAGE 1/16W
J 0
(-960 4450);
DISPLAY 0.617021 (-960 4450);
PAINT SKYBLUE (-960 4450);
FORCEPROP 1 LASTPIN (-1000 4375) $PN 2
J 0
(-995 4385);
DISPLAY 0.617021 (-995 4385);
PAINT ORANGE (-995 4385);
FORCEPROP 1 LAST PART_NUMBER G21796-027
J 0
(-960 4350);
DISPLAY 0.617021 (-960 4350);
PAINT BLUE (-960 4350);
FORCEPROP 2 LAST CDS_LIB mstr_discrete
J 0
(-1000 4475);
PAINT ORANGE (-1000 4475);
DISPLAY INVISIBLE (-1000 4475);
FORCEPROP 2 LAST CDS_LOCATION R9E7
J 0
(-955 4600);
DISPLAY 0.617021 (-955 4600);
PAINT AQUA (-955 4600);
DISPLAY INVISIBLE (-955 4600);
FORCEPROP 2 LAST CDS_SEC 1
J 0
(-950 4700);
PAINT MONO (-950 4700);
DISPLAY INVISIBLE (-950 4700);
FORCEPROP 2 LAST $SEC 1
J 0
(-950 4700);
PAINT MONO (-950 4700);
DISPLAY INVISIBLE (-950 4700);
FORCEPROP 1 LAST PATH I193
J 0
(-950 4650);
DISPLAY 0.978723 (-950 4650);
PAINT WHITE (-950 4650);
DISPLAY INVISIBLE (-950 4650);
FORCEPROP 2 LAST ROOM NIC_SPRV
J 0
(-950 4650);
DISPLAY 1.021277 (-950 4650);
PAINT ORANGE (-950 4650);
DISPLAY INVISIBLE (-950 4650);
FORCEPROP 2 LAST BOM_COST NT_GBE_BASE
J 0
(-950 4700);
DISPLAY 1.021277 (-950 4700);
PAINT ORANGE (-950 4700);
DISPLAY INVISIBLE (-950 4700);
FORCEADD P3V3_STBY..1
(-1000 4700);
FORCEPROP 3 LASTPIN (-1000 4650) SIG_NAME P3V3_STBY\g
J 0
(-990 4660);
DISPLAY 0.659574 (-990 4660);
PAINT MONO (-990 4660);
DISPLAY INVISIBLE (-990 4660);
FORCEPROP 1 LAST VOLTAGE 3.3V
J 0
(-1045 4657);
DISPLAY 0.340426 (-1045 4657);
PAINT SKYBLUE (-1045 4657);
DISPLAY INVISIBLE (-1045 4657);
FORCEPROP 1 LAST PATH I194
J 0
(-955 4702);
DISPLAY 0.340426 (-955 4702);
PAINT GREEN (-955 4702);
DISPLAY INVISIBLE (-955 4702);
FORCEPROP 2 LAST CDS_LIB mstr_symbols
J 0
(-1000 4700);
PAINT ORANGE (-1000 4700);
DISPLAY INVISIBLE (-1000 4700);
FORCEPROP 1 LAST SIZE 1B
J 0
(-955 4722);
DISPLAY 0.340426 (-955 4722);
PAINT GREEN (-955 4722);
DISPLAY INVISIBLE (-955 4722);
FORCEPROP 1 LAST BODY_TYPE PLUMBING
J 0
(-1045 4657);
DISPLAY 0.340426 (-1045 4657);
PAINT GREEN (-1045 4657);
DISPLAY INVISIBLE (-1045 4657);
FORCEPROP 1 LAST HDL_POWER P3V3_STBY
J 0
(-1300 4575);
DISPLAY 0.872340 (-1300 4575);
PAINT ORANGE (-1300 4575);
DISPLAY INVISIBLE (-1300 4575);
FORCEADD RES..1
(-7075 350);
FORCEPROP 1 LASTPIN (-6975 350) $PN 2
J 0
(-7013 362);
DISPLAY 0.617021 (-7013 362);
PAINT ORANGE (-7013 362);
FORCEPROP 1 LASTPIN (-7175 350) $PN 1
J 0
(-7163 362);
DISPLAY 0.617021 (-7163 362);
PAINT ORANGE (-7163 362);
FORCEPROP 1 LAST TOLERANCE 5%
J 0
(-6900 300);
DISPLAY 0.617021 (-6900 300);
PAINT SKYBLUE (-6900 300);
FORCEPROP 1 LAST WATTAGE 1/16W
J 0
(-6800 300);
DISPLAY 0.638298 (-6800 300);
PAINT SKYBLUE (-6800 300);
FORCEPROP 1 LAST LOCATION R1R1
J 0
(-7175 300);
DISPLAY 0.617021 (-7175 300);
PAINT AQUA (-7175 300);
FORCEPROP 1 LAST VALUE 0.0
J 2
(-6950 300);
DISPLAY 0.617021 (-6950 300);
PAINT SKYBLUE (-6950 300);
FORCEPROP 1 LAST PART_NUMBER G21497-005
J 0
(-7050 250);
DISPLAY 0.638298 (-7050 250);
PAINT BLUE (-7050 250);
FORCEPROP 1 LAST MATERIAL CHIP
J 0
(-7175 250);
DISPLAY 0.617021 (-7175 250);
PAINT SKYBLUE (-7175 250);
FORCEPROP 1 LAST PACK_TYPE 0402
J 0
(-6775 250);
DISPLAY 0.638298 (-6775 250);
PAINT SKYBLUE (-6775 250);
FORCEPROP 2 LAST ROOM NIC_SPRV
J 0
(-7125 450);
DISPLAY 1.021277 (-7125 450);
PAINT ORANGE (-7125 450);
DISPLAY INVISIBLE (-7125 450);
FORCEPROP 2 LAST BOM_COST NT_GBE_BASE
J 0
(-7125 500);
DISPLAY 1.021277 (-7125 500);
PAINT ORANGE (-7125 500);
DISPLAY INVISIBLE (-7125 500);
FORCEPROP 2 LAST CDS_LOCATION R1R1
J 0
(-7125 400);
DISPLAY 0.617021 (-7125 400);
PAINT AQUA (-7125 400);
DISPLAY INVISIBLE (-7125 400);
FORCEPROP 2 LAST CDS_LIB mstr_discrete
J 0
(-7075 350);
PAINT ORANGE (-7075 350);
DISPLAY INVISIBLE (-7075 350);
FORCEPROP 1 LAST PATH I195
J 0
(-7125 500);
DISPLAY 0.978723 (-7125 500);
PAINT WHITE (-7125 500);
DISPLAY INVISIBLE (-7125 500);
FORCEPROP 2 LAST SEC_TYPE 0402
J 0
(-7125 550);
DISPLAY 1.021277 (-7125 550);
PAINT ORANGE (-7125 550);
DISPLAY INVISIBLE (-7125 550);
FORCEPROP 2 LAST SEC 1
J 0
(-7125 550);
PAINT MONO (-7125 550);
DISPLAY INVISIBLE (-7125 550);
FORCEADD OFFPAGE..2
(-6025 350);
FORCEPROP 2 LAST $XR0 139 
J 0
(-5836 350);
DISPLAY 0.638298 (-5836 350);
PAINT MONO (-5836 350);
FORCEPROP 2 LAST CDS_LIB mstr_standard
J 0
(-6025 350);
PAINT ORANGE (-6025 350);
DISPLAY INVISIBLE (-6025 350);
FORCEPROP 2 LAST PATH I197
J 0
(-5975 425);
DISPLAY 1.021277 (-5975 425);
PAINT ORANGE (-5975 425);
DISPLAY INVISIBLE (-5975 425);
FORCEPROP 1 LAST OFFPAGE TRUE
J 0
(-5700 225);
DISPLAY 0.872340 (-5700 225);
PAINT GREEN (-5700 225);
DISPLAY INVISIBLE (-5700 225);
FORCEPROP 1 LAST COMMENT_BODY TRUE
J 0
(-6070 255);
DISPLAY 0.872340 (-6070 255);
PAINT GREEN (-6070 255);
DISPLAY INVISIBLE (-6070 255);
FORCEADD OFFPAGE..1
(-7600 350);
FORCEPROP 2 LAST $XR3 247 
J 0
(-7882 422);
DISPLAY 0.638298 (-7882 422);
PAINT MONO (-7882 422);
FORCEPROP 2 LAST $XR2 191 
J 0
(-7882 386);
DISPLAY 0.638298 (-7882 386);
PAINT MONO (-7882 386);
FORCEPROP 2 LAST $XR1 136 
J 0
(-7882 314);
DISPLAY 0.638298 (-7882 314);
PAINT MONO (-7882 314);
FORCEPROP 2 LAST $XR0 119 
J 0
(-7882 350);
DISPLAY 0.638298 (-7882 350);
PAINT MONO (-7882 350);
FORCEPROP 2 LAST CDS_LIB mstr_standard
J 0
(-7600 350);
PAINT ORANGE (-7600 350);
DISPLAY INVISIBLE (-7600 350);
FORCEPROP 2 LAST PATH I198
J 0
(-7550 425);
DISPLAY 1.021277 (-7550 425);
PAINT ORANGE (-7550 425);
DISPLAY INVISIBLE (-7550 425);
FORCEPROP 1 LAST OFFPAGE TRUE
J 0
(-7275 225);
DISPLAY 0.872340 (-7275 225);
PAINT GREEN (-7275 225);
DISPLAY INVISIBLE (-7275 225);
FORCEPROP 1 LAST COMMENT_BODY TRUE
J 0
(-7475 250);
DISPLAY 0.872340 (-7475 250);
PAINT GREEN (-7475 250);
DISPLAY INVISIBLE (-7475 250);
FORCEADD P3V3_STBY..1
(-6925 800);
FORCEPROP 3 LASTPIN (-6925 750) SIG_NAME P3V3_STBY\g
J 0
(-6915 760);
DISPLAY 0.659574 (-6915 760);
PAINT MONO (-6915 760);
DISPLAY INVISIBLE (-6915 760);
FORCEPROP 1 LAST HDL_POWER P3V3_STBY
J 0
(-7225 675);
DISPLAY 0.872340 (-7225 675);
PAINT ORANGE (-7225 675);
DISPLAY INVISIBLE (-7225 675);
FORCEPROP 1 LAST BODY_TYPE PLUMBING
J 0
(-6970 757);
DISPLAY 0.340426 (-6970 757);
PAINT GREEN (-6970 757);
DISPLAY INVISIBLE (-6970 757);
FORCEPROP 1 LAST SIZE 1B
J 0
(-6880 822);
DISPLAY 0.340426 (-6880 822);
PAINT GREEN (-6880 822);
DISPLAY INVISIBLE (-6880 822);
FORCEPROP 2 LAST CDS_LIB mstr_symbols
J 0
(-6925 800);
PAINT ORANGE (-6925 800);
DISPLAY INVISIBLE (-6925 800);
FORCEPROP 1 LAST PATH I199
J 0
(-6880 802);
DISPLAY 0.340426 (-6880 802);
PAINT GREEN (-6880 802);
DISPLAY INVISIBLE (-6880 802);
FORCEPROP 1 LAST VOLTAGE 3.3V
J 0
(-6970 757);
DISPLAY 0.340426 (-6970 757);
PAINT SKYBLUE (-6970 757);
DISPLAY INVISIBLE (-6970 757);
FORCEADD RES..2
(-6925 550);
FORCEPROP 1 LAST VALUE 10.0K
J 0
(-6880 625);
DISPLAY 0.617021 (-6880 625);
PAINT SKYBLUE (-6880 625);
FORCEPROP 1 LAST PART_NUMBER G21796-016
J 0
(-6885 425);
DISPLAY 0.617021 (-6885 425);
PAINT BLUE (-6885 425);
FORCEPROP 1 LAST MATERIAL CHIP
J 0
(-6885 475);
DISPLAY 0.617021 (-6885 475);
PAINT SKYBLUE (-6885 475);
FORCEPROP 1 LAST WATTAGE 1/16W
J 0
(-6885 525);
DISPLAY 0.617021 (-6885 525);
PAINT SKYBLUE (-6885 525);
FORCEPROP 1 LAST PACK_TYPE 0402
J 0
(-6885 375);
DISPLAY 0.617021 (-6885 375);
PAINT SKYBLUE (-6885 375);
FORCEPROP 1 LAST TOLERANCE 1%
J 0
(-6880 575);
DISPLAY 0.617021 (-6880 575);
PAINT SKYBLUE (-6880 575);
FORCEPROP 1 LASTPIN (-6925 650) $PN 1
J 0
(-6920 612);
DISPLAY 0.617021 (-6920 612);
PAINT ORANGE (-6920 612);
FORCEPROP 1 LASTPIN (-6925 450) $PN 2
J 0
(-6920 460);
DISPLAY 0.617021 (-6920 460);
PAINT ORANGE (-6920 460);
FORCEPROP 1 LAST LOCATION R9E4
J 0
(-6880 675);
DISPLAY 0.617021 (-6880 675);
PAINT AQUA (-6880 675);
FORCEPROP 2 LAST BOM_COST NT_GBE_BASE
J 0
(-6875 775);
DISPLAY 1.021277 (-6875 775);
PAINT ORANGE (-6875 775);
DISPLAY INVISIBLE (-6875 775);
FORCEPROP 2 LAST SEC_TYPE 0402
J 0
(-6875 775);
DISPLAY 1.021277 (-6875 775);
PAINT ORANGE (-6875 775);
DISPLAY INVISIBLE (-6875 775);
FORCEPROP 2 LAST SEC 1
J 0
(-6875 775);
PAINT MONO (-6875 775);
DISPLAY INVISIBLE (-6875 775);
FORCEPROP 2 LAST ROOM NIC_SPRV
J 0
(-6875 725);
DISPLAY 1.021277 (-6875 725);
PAINT ORANGE (-6875 725);
DISPLAY INVISIBLE (-6875 725);
FORCEPROP 1 LAST PATH I200
J 0
(-6875 725);
DISPLAY 0.978723 (-6875 725);
PAINT WHITE (-6875 725);
DISPLAY INVISIBLE (-6875 725);
FORCEPROP 2 LAST CDS_LOCATION R9E4
J 0
(-6880 675);
DISPLAY 0.617021 (-6880 675);
PAINT AQUA (-6880 675);
DISPLAY INVISIBLE (-6880 675);
FORCEPROP 2 LAST CDS_LIB mstr_discrete
J 0
(-6925 550);
PAINT ORANGE (-6925 550);
DISPLAY INVISIBLE (-6925 550);
FORCEADD RES..1
(-6800 1575);
FORCEPROP 1 LAST LOCATION R9E18
J 0
(-7050 1525);
DISPLAY 0.617021 (-7050 1525);
PAINT AQUA (-7050 1525);
FORCEPROP 1 LASTPIN (-6900 1575) $PN 1
J 0
(-6888 1587);
DISPLAY 0.617021 (-6888 1587);
PAINT ORANGE (-6888 1587);
FORCEPROP 1 LASTPIN (-6700 1575) $PN 2
J 0
(-6738 1587);
DISPLAY 0.617021 (-6738 1587);
PAINT ORANGE (-6738 1587);
FORCEPROP 1 LAST TOLERANCE 5%
J 0
(-6750 1525);
DISPLAY 0.617021 (-6750 1525);
PAINT SKYBLUE (-6750 1525);
FORCEPROP 1 LAST WATTAGE 1/16W
J 0
(-6650 1525);
DISPLAY 0.638298 (-6650 1525);
PAINT SKYBLUE (-6650 1525);
FORCEPROP 1 LAST PACK_TYPE 0402
J 0
(-6625 1475);
DISPLAY 0.638298 (-6625 1475);
PAINT SKYBLUE (-6625 1475);
FORCEPROP 1 LAST MATERIAL CHIP
J 0
(-7050 1475);
DISPLAY 0.617021 (-7050 1475);
PAINT SKYBLUE (-7050 1475);
FORCEPROP 0 LAST GROUP NI_I210&RJ45
J 0
(-7044 1438);
DISPLAY 0.638298 (-7044 1438);
PAINT BROWN (-7044 1438);
DISPLAY BOTH (-7044 1438);
FORCEPROP 1 LAST PART_NUMBER G21497-005
J 0
(-6900 1475);
DISPLAY 0.638298 (-6900 1475);
PAINT BLUE (-6900 1475);
FORCEPROP 1 LAST VALUE 0.0
J 2
(-6800 1525);
DISPLAY 0.617021 (-6800 1525);
PAINT SKYBLUE (-6800 1525);
FORCEPROP 2 LAST BOM_COST NT_GBE_BASE
J 0
(-6850 1725);
DISPLAY 1.021277 (-6850 1725);
PAINT ORANGE (-6850 1725);
DISPLAY INVISIBLE (-6850 1725);
FORCEPROP 2 LAST CDS_LOCATION R9E18
J 0
(-6850 1625);
DISPLAY 0.617021 (-6850 1625);
PAINT AQUA (-6850 1625);
DISPLAY INVISIBLE (-6850 1625);
FORCEPROP 1 LAST PATH I201
J 0
(-6850 1725);
DISPLAY 0.978723 (-6850 1725);
PAINT WHITE (-6850 1725);
DISPLAY INVISIBLE (-6850 1725);
FORCEPROP 2 LAST ROOM NIC_SPRV
J 0
(-6850 1675);
DISPLAY 1.021277 (-6850 1675);
PAINT ORANGE (-6850 1675);
DISPLAY INVISIBLE (-6850 1675);
FORCEPROP 2 LAST SEC_TYPE 0402
J 0
(-6850 1775);
DISPLAY 1.021277 (-6850 1775);
PAINT ORANGE (-6850 1775);
DISPLAY INVISIBLE (-6850 1775);
FORCEPROP 2 LAST SEC 1
J 0
(-6850 1775);
PAINT MONO (-6850 1775);
DISPLAY INVISIBLE (-6850 1775);
FORCEPROP 2 LAST CDS_LIB mstr_discrete
J 0
(-6800 1575);
PAINT ORANGE (-6800 1575);
DISPLAY INVISIBLE (-6800 1575);
FORCEADD OFFPAGE..1
(-6900 2275);
FORCEPROP 2 LAST $XR0 139 
J 0
(-7152 2275);
DISPLAY 0.638298 (-7152 2275);
PAINT MONO (-7152 2275);
FORCEPROP 1 LAST COMMENT_BODY TRUE
J 0
(-6775 2175);
DISPLAY 0.872340 (-6775 2175);
PAINT GREEN (-6775 2175);
DISPLAY INVISIBLE (-6775 2175);
FORCEPROP 1 LAST OFFPAGE TRUE
J 0
(-6575 2150);
DISPLAY 0.872340 (-6575 2150);
PAINT GREEN (-6575 2150);
DISPLAY INVISIBLE (-6575 2150);
FORCEPROP 2 LAST PATH I202
J 0
(-6850 2350);
DISPLAY 1.021277 (-6850 2350);
PAINT ORANGE (-6850 2350);
DISPLAY INVISIBLE (-6850 2350);
FORCEPROP 2 LAST CDS_LIB mstr_standard
J 0
(-6900 2275);
PAINT ORANGE (-6900 2275);
DISPLAY INVISIBLE (-6900 2275);
FORCEADD OFFPAGE..2
(-1000 1825);
FORCEPROP 2 LAST $XR3 139 
J 0
(-451 1825);
DISPLAY 0.638298 (-451 1825);
PAINT MONO (-451 1825);
FORCEPROP 2 LAST $XR2 121 
J 0
(-571 1825);
DISPLAY 0.638298 (-571 1825);
PAINT MONO (-571 1825);
FORCEPROP 2 LAST $XR1 150 
J 0
(-691 1825);
DISPLAY 0.638298 (-691 1825);
PAINT MONO (-691 1825);
FORCEPROP 2 LAST $XR0 147 
J 0
(-811 1825);
DISPLAY 0.638298 (-811 1825);
PAINT MONO (-811 1825);
FORCEPROP 2 LAST CDS_LIB mstr_standard
J 0
(-1000 1825);
PAINT ORANGE (-1000 1825);
DISPLAY INVISIBLE (-1000 1825);
FORCEPROP 2 LAST PATH I203
J 0
(-800 1875);
DISPLAY 1.021277 (-800 1875);
PAINT ORANGE (-800 1875);
DISPLAY INVISIBLE (-800 1875);
FORCEPROP 1 LAST OFFPAGE TRUE
J 0
(-675 1700);
DISPLAY 0.872340 (-675 1700);
PAINT GREEN (-675 1700);
DISPLAY INVISIBLE (-675 1700);
FORCEPROP 1 LAST COMMENT_BODY TRUE
J 0
(-1045 1730);
DISPLAY 0.872340 (-1045 1730);
PAINT GREEN (-1045 1730);
DISPLAY INVISIBLE (-1045 1730);
FORCEADD GND..1
(-1900 1375);
FORCEPROP 3 LASTPIN (-1900 1425) SIG_NAME GND\g
J 0
(-1890 1435);
DISPLAY 0.659574 (-1890 1435);
PAINT MONO (-1890 1435);
DISPLAY INVISIBLE (-1890 1435);
FORCEPROP 1 LAST PATH I204
J 0
(-1825 1375);
DISPLAY 0.872340 (-1825 1375);
PAINT AQUA (-1825 1375);
DISPLAY INVISIBLE (-1825 1375);
FORCEPROP 2 LAST CDS_LIB mstr_symbols
J 0
(-1900 1375);
PAINT ORANGE (-1900 1375);
DISPLAY INVISIBLE (-1900 1375);
FORCEPROP 1 LAST SIZE 1B
J 0
(-1825 1325);
DISPLAY 0.872340 (-1825 1325);
PAINT AQUA (-1825 1325);
DISPLAY INVISIBLE (-1825 1325);
FORCEPROP 1 LAST VOLTAGE 0.0V
J 0
(-1945 1332);
DISPLAY 0.340426 (-1945 1332);
PAINT SKYBLUE (-1945 1332);
DISPLAY INVISIBLE (-1945 1332);
FORCEPROP 1 LAST BODY_TYPE PLUMBING
J 0
(-1945 1332);
DISPLAY 0.340426 (-1945 1332);
PAINT GREEN (-1945 1332);
DISPLAY INVISIBLE (-1945 1332);
FORCEPROP 1 LAST HDL_POWER GND
J 0
(-1900 1525);
DISPLAY 0.872340 (-1900 1525);
PAINT GREEN (-1900 1525);
DISPLAY INVISIBLE (-1900 1525);
FORCEADD OFFPAGE..2
(-2350 1700);
FORCEPROP 2 LAST $XR1 139 
J 0
(-2041 1700);
DISPLAY 0.638298 (-2041 1700);
PAINT MONO (-2041 1700);
FORCEPROP 2 LAST $XR0 101 
J 0
(-2161 1700);
DISPLAY 0.638298 (-2161 1700);
PAINT MONO (-2161 1700);
FORCEPROP 1 LAST COMMENT_BODY TRUE
J 0
(-2395 1605);
DISPLAY 0.872340 (-2395 1605);
PAINT GREEN (-2395 1605);
DISPLAY INVISIBLE (-2395 1605);
FORCEPROP 1 LAST OFFPAGE TRUE
J 0
(-2025 1575);
DISPLAY 0.872340 (-2025 1575);
PAINT GREEN (-2025 1575);
DISPLAY INVISIBLE (-2025 1575);
FORCEPROP 2 LAST PATH I206
J 0
(-2150 1750);
DISPLAY 1.021277 (-2150 1750);
PAINT ORANGE (-2150 1750);
DISPLAY INVISIBLE (-2150 1750);
FORCEPROP 2 LAST CDS_LIB mstr_standard
J 0
(-2350 1700);
PAINT ORANGE (-2350 1700);
DISPLAY INVISIBLE (-2350 1700);
FORCEADD GND..1
(-3050 1225);
FORCEPROP 3 LASTPIN (-3050 1275) SIG_NAME GND\g
J 0
(-3040 1285);
DISPLAY 0.659574 (-3040 1285);
PAINT MONO (-3040 1285);
DISPLAY INVISIBLE (-3040 1285);
FORCEPROP 1 LAST VOLTAGE 0.0V
J 0
(-3095 1182);
DISPLAY 0.340426 (-3095 1182);
PAINT SKYBLUE (-3095 1182);
DISPLAY INVISIBLE (-3095 1182);
FORCEPROP 2 LAST CDS_LIB mstr_symbols
J 0
(-3050 1225);
PAINT ORANGE (-3050 1225);
DISPLAY INVISIBLE (-3050 1225);
FORCEPROP 1 LAST PATH I207
J 0
(-2975 1225);
DISPLAY 0.872340 (-2975 1225);
PAINT AQUA (-2975 1225);
DISPLAY INVISIBLE (-2975 1225);
FORCEPROP 1 LAST SIZE 1B
J 0
(-2975 1175);
DISPLAY 0.872340 (-2975 1175);
PAINT AQUA (-2975 1175);
DISPLAY INVISIBLE (-2975 1175);
FORCEPROP 1 LAST BODY_TYPE PLUMBING
J 0
(-3095 1182);
DISPLAY 0.340426 (-3095 1182);
PAINT GREEN (-3095 1182);
DISPLAY INVISIBLE (-3095 1182);
FORCEPROP 1 LAST HDL_POWER GND
J 0
(-3050 1375);
DISPLAY 0.872340 (-3050 1375);
PAINT GREEN (-3050 1375);
DISPLAY INVISIBLE (-3050 1375);
FORCEADD OFFPAGE..2
(-350 1725);
FORCEPROP 2 LAST $XR2 147 
J 0
(-161 1761);
DISPLAY 0.638298 (-161 1761);
PAINT MONO (-161 1761);
FORCEPROP 2 LAST $XR1 139 
J 0
(-161 1689);
DISPLAY 0.638298 (-161 1689);
PAINT MONO (-161 1689);
FORCEPROP 2 LAST $XR0 121 
J 0
(-161 1725);
DISPLAY 0.638298 (-161 1725);
PAINT MONO (-161 1725);
FORCEPROP 1 LAST COMMENT_BODY TRUE
J 0
(-395 1630);
DISPLAY 0.872340 (-395 1630);
PAINT GREEN (-395 1630);
DISPLAY INVISIBLE (-395 1630);
FORCEPROP 1 LAST OFFPAGE TRUE
J 0
(-25 1600);
DISPLAY 0.872340 (-25 1600);
PAINT GREEN (-25 1600);
DISPLAY INVISIBLE (-25 1600);
FORCEPROP 2 LAST PATH I209
J 0
(-150 1775);
DISPLAY 1.021277 (-150 1775);
PAINT ORANGE (-150 1775);
DISPLAY INVISIBLE (-150 1775);
FORCEPROP 2 LAST CDS_LIB mstr_standard
J 0
(-350 1725);
PAINT ORANGE (-350 1725);
DISPLAY INVISIBLE (-350 1725);
FORCEADD GND..1
(-1300 1350);
FORCEPROP 3 LASTPIN (-1300 1400) SIG_NAME GND\g
J 0
(-1290 1410);
DISPLAY 0.659574 (-1290 1410);
PAINT MONO (-1290 1410);
DISPLAY INVISIBLE (-1290 1410);
FORCEPROP 1 LAST VOLTAGE 0.0V
J 0
(-1345 1307);
DISPLAY 0.340426 (-1345 1307);
PAINT SKYBLUE (-1345 1307);
DISPLAY INVISIBLE (-1345 1307);
FORCEPROP 1 LAST SIZE 1B
J 0
(-1225 1300);
DISPLAY 0.872340 (-1225 1300);
PAINT AQUA (-1225 1300);
DISPLAY INVISIBLE (-1225 1300);
FORCEPROP 2 LAST CDS_LIB mstr_symbols
J 0
(-1300 1350);
PAINT ORANGE (-1300 1350);
DISPLAY INVISIBLE (-1300 1350);
FORCEPROP 1 LAST PATH I211
J 0
(-1225 1350);
DISPLAY 0.872340 (-1225 1350);
PAINT AQUA (-1225 1350);
DISPLAY INVISIBLE (-1225 1350);
FORCEPROP 1 LAST BODY_TYPE PLUMBING
J 0
(-1345 1307);
DISPLAY 0.340426 (-1345 1307);
PAINT GREEN (-1345 1307);
DISPLAY INVISIBLE (-1345 1307);
FORCEPROP 1 LAST HDL_POWER GND
J 0
(-1300 1500);
DISPLAY 0.872340 (-1300 1500);
PAINT GREEN (-1300 1500);
DISPLAY INVISIBLE (-1300 1500);
FORCEADD RES..2
(-1900 1650);
FORCEPROP 1 LASTPIN (-1900 1550) $PN 2
J 0
(-1895 1560);
DISPLAY 0.617021 (-1895 1560);
PAINT ORANGE (-1895 1560);
FORCEPROP 1 LAST TOLERANCE 1%
J 0
(-1855 1675);
DISPLAY 0.617021 (-1855 1675);
PAINT SKYBLUE (-1855 1675);
FORCEPROP 1 LAST MATERIAL CHIP
J 0
(-1860 1575);
DISPLAY 0.617021 (-1860 1575);
PAINT SKYBLUE (-1860 1575);
FORCEPROP 1 LAST PACK_TYPE 0402
J 0
(-1860 1475);
DISPLAY 0.617021 (-1860 1475);
PAINT SKYBLUE (-1860 1475);
FORCEPROP 1 LAST PART_NUMBER G21796-016
J 0
(-1860 1525);
DISPLAY 0.617021 (-1860 1525);
PAINT BLUE (-1860 1525);
FORCEPROP 1 LAST WATTAGE 1/16W
J 0
(-1860 1625);
DISPLAY 0.617021 (-1860 1625);
PAINT SKYBLUE (-1860 1625);
FORCEPROP 1 LAST LOCATION R9E13
J 0
(-1855 1775);
DISPLAY 0.617021 (-1855 1775);
PAINT AQUA (-1855 1775);
FORCEPROP 1 LASTPIN (-1900 1750) $PN 1
J 0
(-1895 1712);
DISPLAY 0.617021 (-1895 1712);
PAINT ORANGE (-1895 1712);
FORCEPROP 1 LAST VALUE 10.0K
J 0
(-1855 1725);
DISPLAY 0.617021 (-1855 1725);
PAINT SKYBLUE (-1855 1725);
FORCEPROP 2 LAST CDS_LIB mstr_discrete
J 0
(-1900 1650);
PAINT ORANGE (-1900 1650);
DISPLAY INVISIBLE (-1900 1650);
FORCEPROP 2 LAST CDS_LOCATION R9E13
J 0
(-1855 1775);
DISPLAY 0.617021 (-1855 1775);
PAINT AQUA (-1855 1775);
DISPLAY INVISIBLE (-1855 1775);
FORCEPROP 1 LAST PATH I212
J 0
(-1850 1825);
DISPLAY 0.978723 (-1850 1825);
PAINT WHITE (-1850 1825);
DISPLAY INVISIBLE (-1850 1825);
FORCEPROP 2 LAST ROOM NIC_SPRV
J 0
(-1850 1825);
DISPLAY 1.021277 (-1850 1825);
PAINT ORANGE (-1850 1825);
DISPLAY INVISIBLE (-1850 1825);
FORCEPROP 2 LAST BOM_COST NT_GBE_BASE
J 0
(-1850 1875);
DISPLAY 1.021277 (-1850 1875);
PAINT ORANGE (-1850 1875);
DISPLAY INVISIBLE (-1850 1875);
FORCEPROP 2 LAST CDS_SEC 1
J 0
(-1850 1875);
PAINT MONO (-1850 1875);
DISPLAY INVISIBLE (-1850 1875);
FORCEPROP 2 LAST $SEC 1
J 0
(-1850 1875);
PAINT MONO (-1850 1875);
DISPLAY INVISIBLE (-1850 1875);
FORCEADD RES..2
(-3050 1500);
FORCEPROP 0 LAST GROUP NI_I210&RJ45
J 0
(-2994 1288);
DISPLAY 0.638298 (-2994 1288);
PAINT BROWN (-2994 1288);
DISPLAY BOTH (-2994 1288);
FORCEPROP 1 LAST PACK_TYPE 0402
J 0
(-3010 1325);
DISPLAY 0.617021 (-3010 1325);
PAINT SKYBLUE (-3010 1325);
FORCEPROP 1 LAST PART_NUMBER G21796-016
J 0
(-3010 1375);
DISPLAY 0.617021 (-3010 1375);
PAINT BLUE (-3010 1375);
FORCEPROP 1 LASTPIN (-3050 1400) $PN 2
J 0
(-3045 1410);
DISPLAY 0.617021 (-3045 1410);
PAINT ORANGE (-3045 1410);
FORCEPROP 1 LAST MATERIAL CHIP
J 0
(-3010 1425);
DISPLAY 0.617021 (-3010 1425);
PAINT SKYBLUE (-3010 1425);
FORCEPROP 1 LAST TOLERANCE 1%
J 0
(-3005 1525);
DISPLAY 0.617021 (-3005 1525);
PAINT SKYBLUE (-3005 1525);
FORCEPROP 1 LAST WATTAGE 1/16W
J 0
(-3010 1475);
DISPLAY 0.617021 (-3010 1475);
PAINT SKYBLUE (-3010 1475);
FORCEPROP 1 LASTPIN (-3050 1600) $PN 1
J 0
(-3045 1562);
DISPLAY 0.617021 (-3045 1562);
PAINT ORANGE (-3045 1562);
FORCEPROP 1 LAST LOCATION R1R12
J 0
(-3005 1625);
DISPLAY 0.617021 (-3005 1625);
PAINT AQUA (-3005 1625);
FORCEPROP 1 LAST VALUE 10.0K
J 0
(-3005 1575);
DISPLAY 0.617021 (-3005 1575);
PAINT SKYBLUE (-3005 1575);
FORCEPROP 2 LAST CDS_LIB mstr_discrete
J 0
(-3050 1500);
PAINT ORANGE (-3050 1500);
DISPLAY INVISIBLE (-3050 1500);
FORCEPROP 2 LAST BOM_COST NT_GBE_BASE
J 0
(-3000 1725);
DISPLAY 1.021277 (-3000 1725);
PAINT ORANGE (-3000 1725);
DISPLAY INVISIBLE (-3000 1725);
FORCEPROP 2 LAST CDS_SEC 1
J 0
(-3000 1725);
PAINT MONO (-3000 1725);
DISPLAY INVISIBLE (-3000 1725);
FORCEPROP 2 LAST $SEC 1
J 0
(-3000 1725);
PAINT MONO (-3000 1725);
DISPLAY INVISIBLE (-3000 1725);
FORCEPROP 2 LAST CDS_LOCATION R1R12
J 0
(-3005 1625);
DISPLAY 0.617021 (-3005 1625);
PAINT AQUA (-3005 1625);
DISPLAY INVISIBLE (-3005 1625);
FORCEPROP 1 LAST PATH I213
J 0
(-3000 1675);
DISPLAY 0.978723 (-3000 1675);
PAINT WHITE (-3000 1675);
DISPLAY INVISIBLE (-3000 1675);
FORCEPROP 2 LAST ROOM NIC_SPRV
J 0
(-3000 1675);
DISPLAY 1.021277 (-3000 1675);
PAINT ORANGE (-3000 1675);
DISPLAY INVISIBLE (-3000 1675);
FORCEADD RES..2
(-1300 1550);
FORCEPROP 1 LAST MATERIAL CHIP
J 0
(-1260 1475);
DISPLAY 0.617021 (-1260 1475);
PAINT SKYBLUE (-1260 1475);
FORCEPROP 1 LAST WATTAGE 1/16W
J 0
(-1260 1525);
DISPLAY 0.617021 (-1260 1525);
PAINT SKYBLUE (-1260 1525);
FORCEPROP 1 LAST PACK_TYPE 0402
J 0
(-1260 1375);
DISPLAY 0.617021 (-1260 1375);
PAINT SKYBLUE (-1260 1375);
FORCEPROP 1 LAST VALUE 10.0K
J 0
(-1255 1625);
DISPLAY 0.617021 (-1255 1625);
PAINT SKYBLUE (-1255 1625);
FORCEPROP 1 LASTPIN (-1300 1450) $PN 2
J 0
(-1295 1460);
DISPLAY 0.617021 (-1295 1460);
PAINT ORANGE (-1295 1460);
FORCEPROP 1 LAST TOLERANCE 1%
J 0
(-1255 1575);
DISPLAY 0.617021 (-1255 1575);
PAINT SKYBLUE (-1255 1575);
FORCEPROP 1 LASTPIN (-1300 1650) $PN 1
J 0
(-1295 1612);
DISPLAY 0.617021 (-1295 1612);
PAINT ORANGE (-1295 1612);
FORCEPROP 1 LAST LOCATION R1T1
J 0
(-1255 1675);
DISPLAY 0.617021 (-1255 1675);
PAINT AQUA (-1255 1675);
FORCEPROP 1 LAST PART_NUMBER G21796-016
J 0
(-1260 1425);
DISPLAY 0.617021 (-1260 1425);
PAINT BLUE (-1260 1425);
FORCEPROP 2 LAST BOM_COST NT_GBE_BASE
J 0
(-1250 1775);
DISPLAY 1.021277 (-1250 1775);
PAINT ORANGE (-1250 1775);
DISPLAY INVISIBLE (-1250 1775);
FORCEPROP 2 LAST CDS_SEC 1
J 0
(-1250 1775);
PAINT MONO (-1250 1775);
DISPLAY INVISIBLE (-1250 1775);
FORCEPROP 2 LAST $SEC 1
J 0
(-1250 1775);
PAINT MONO (-1250 1775);
DISPLAY INVISIBLE (-1250 1775);
FORCEPROP 1 LAST PATH I214
J 0
(-1250 1725);
DISPLAY 0.978723 (-1250 1725);
PAINT WHITE (-1250 1725);
DISPLAY INVISIBLE (-1250 1725);
FORCEPROP 2 LAST CDS_LOCATION R1T1
J 0
(-1255 1675);
DISPLAY 0.617021 (-1255 1675);
PAINT AQUA (-1255 1675);
DISPLAY INVISIBLE (-1255 1675);
FORCEPROP 2 LAST ROOM NIC_SPRV
J 0
(-1250 1725);
DISPLAY 1.021277 (-1250 1725);
PAINT ORANGE (-1250 1725);
DISPLAY INVISIBLE (-1250 1725);
FORCEPROP 2 LAST CDS_LIB mstr_discrete
J 0
(-1300 1550);
PAINT ORANGE (-1300 1550);
DISPLAY INVISIBLE (-1300 1550);
FORCEADD OFFPAGE..4
(-2350 3025);
FORCEPROP 2 LAST $XR0 159 
J 0
(-2164 3025);
DISPLAY 0.638298 (-2164 3025);
PAINT MONO (-2164 3025);
FORCEPROP 1 LAST COMMENT_BODY TRUE
J 0
(-2375 2925);
DISPLAY 0.872340 (-2375 2925);
PAINT GREEN (-2375 2925);
DISPLAY INVISIBLE (-2375 2925);
FORCEPROP 1 LAST OFFPAGE TRUE
J 0
(-2025 2900);
DISPLAY 0.872340 (-2025 2900);
PAINT GREEN (-2025 2900);
DISPLAY INVISIBLE (-2025 2900);
FORCEPROP 2 LAST CDS_LIB mstr_standard
J 0
(-2350 3025);
PAINT ORANGE (-2350 3025);
DISPLAY INVISIBLE (-2350 3025);
FORCEPROP 2 LAST PATH I218
J 0
(-2300 3100);
DISPLAY 1.021277 (-2300 3100);
PAINT ORANGE (-2300 3100);
DISPLAY INVISIBLE (-2300 3100);
FORCEADD OFFPAGE..4
(-2350 2975);
FORCEPROP 2 LAST $XR0 159 
J 0
(-2164 2975);
DISPLAY 0.638298 (-2164 2975);
PAINT MONO (-2164 2975);
FORCEPROP 2 LAST CDS_LIB mstr_standard
J 0
(-2350 2975);
PAINT ORANGE (-2350 2975);
DISPLAY INVISIBLE (-2350 2975);
FORCEPROP 2 LAST PATH I219
J 0
(-2175 3050);
DISPLAY 1.021277 (-2175 3050);
PAINT ORANGE (-2175 3050);
DISPLAY INVISIBLE (-2175 3050);
FORCEPROP 1 LAST OFFPAGE TRUE
J 0
(-2025 2850);
DISPLAY 0.872340 (-2025 2850);
PAINT GREEN (-2025 2850);
DISPLAY INVISIBLE (-2025 2850);
FORCEPROP 1 LAST COMMENT_BODY TRUE
J 0
(-2375 2875);
DISPLAY 0.872340 (-2375 2875);
PAINT GREEN (-2375 2875);
DISPLAY INVISIBLE (-2375 2875);
FORCEADD OFFPAGE..2
(-2350 2925);
FORCEPROP 2 LAST $XR2 146 
J 0
(-1921 2925);
DISPLAY 0.638298 (-1921 2925);
PAINT MONO (-1921 2925);
FORCEPROP 2 LAST $XR1 119 
J 0
(-2041 2925);
DISPLAY 0.638298 (-2041 2925);
PAINT MONO (-2041 2925);
FORCEPROP 2 LAST $XR0 139 
J 0
(-2161 2925);
DISPLAY 0.638298 (-2161 2925);
PAINT MONO (-2161 2925);
FORCEPROP 2 LAST CDS_LIB mstr_standard
J 0
(-2350 2925);
PAINT ORANGE (-2350 2925);
DISPLAY INVISIBLE (-2350 2925);
FORCEPROP 2 LAST PATH I220
J 0
(-2175 3000);
DISPLAY 1.021277 (-2175 3000);
PAINT ORANGE (-2175 3000);
DISPLAY INVISIBLE (-2175 3000);
FORCEPROP 1 LAST OFFPAGE TRUE
J 0
(-2025 2800);
DISPLAY 0.872340 (-2025 2800);
PAINT GREEN (-2025 2800);
DISPLAY INVISIBLE (-2025 2800);
FORCEPROP 1 LAST COMMENT_BODY TRUE
J 0
(-2395 2830);
DISPLAY 0.872340 (-2395 2830);
PAINT GREEN (-2395 2830);
DISPLAY INVISIBLE (-2395 2830);
FORCEADD OFFPAGE..1
(-6900 2475);
FORCEPROP 2 LAST $XR1 121 
J 0
(-7272 2475);
DISPLAY 0.638298 (-7272 2475);
PAINT MONO (-7272 2475);
FORCEPROP 2 LAST $XR0 147 
J 0
(-7152 2475);
DISPLAY 0.638298 (-7152 2475);
PAINT MONO (-7152 2475);
FORCEPROP 1 LAST COMMENT_BODY TRUE
J 0
(-6775 2375);
DISPLAY 0.872340 (-6775 2375);
PAINT GREEN (-6775 2375);
DISPLAY INVISIBLE (-6775 2375);
FORCEPROP 1 LAST OFFPAGE TRUE
J 0
(-6575 2350);
DISPLAY 0.872340 (-6575 2350);
PAINT GREEN (-6575 2350);
DISPLAY INVISIBLE (-6575 2350);
FORCEPROP 2 LAST PATH I223
J 0
(-6850 2550);
DISPLAY 1.021277 (-6850 2550);
PAINT ORANGE (-6850 2550);
DISPLAY INVISIBLE (-6850 2550);
FORCEPROP 2 LAST CDS_LIB mstr_standard
J 0
(-6900 2475);
PAINT ORANGE (-6900 2475);
DISPLAY INVISIBLE (-6900 2475);
FORCEADD OFFPAGE..1
(-6900 2525);
FORCEPROP 2 LAST $XR1 121 
J 0
(-7272 2525);
DISPLAY 0.638298 (-7272 2525);
PAINT MONO (-7272 2525);
FORCEPROP 2 LAST $XR0 147 
J 0
(-7152 2525);
DISPLAY 0.638298 (-7152 2525);
PAINT MONO (-7152 2525);
FORCEPROP 1 LAST COMMENT_BODY TRUE
J 0
(-6775 2425);
DISPLAY 0.872340 (-6775 2425);
PAINT GREEN (-6775 2425);
DISPLAY INVISIBLE (-6775 2425);
FORCEPROP 1 LAST OFFPAGE TRUE
J 0
(-6575 2400);
DISPLAY 0.872340 (-6575 2400);
PAINT GREEN (-6575 2400);
DISPLAY INVISIBLE (-6575 2400);
FORCEPROP 2 LAST PATH I224
J 0
(-6850 2600);
DISPLAY 1.021277 (-6850 2600);
PAINT ORANGE (-6850 2600);
DISPLAY INVISIBLE (-6850 2600);
FORCEPROP 2 LAST CDS_LIB mstr_standard
J 0
(-6900 2525);
PAINT ORANGE (-6900 2525);
DISPLAY INVISIBLE (-6900 2525);
FORCEADD RES..1
(-2400 2675);
FORCEPROP 1 LAST WATTAGE 1/16W
J 2
(-2125 2625);
DISPLAY 0.617021 (-2125 2625);
PAINT SKYBLUE (-2125 2625);
FORCEPROP 1 LAST VALUE 22.1
J 2
(-2425 2625);
DISPLAY 0.617021 (-2425 2625);
PAINT SKYBLUE (-2425 2625);
FORCEPROP 1 LAST TOLERANCE 1.0%
J 0
(-2350 2625);
DISPLAY 0.617021 (-2350 2625);
PAINT SKYBLUE (-2350 2625);
FORCEPROP 1 LAST LOCATION R9F1
J 0
(-2350 2675);
DISPLAY 0.617021 (-2350 2675);
PAINT AQUA (-2350 2675);
FORCEPROP 1 LAST PART_NUMBER G21796-250
J 0
(-2850 2625);
DISPLAY 0.617021 (-2850 2625);
PAINT BLUE (-2850 2625);
FORCEPROP 1 LAST MATERIAL CHIP
J 0
(-2625 2625);
DISPLAY 0.617021 (-2625 2625);
PAINT SKYBLUE (-2625 2625);
FORCEPROP 1 LAST PACK_TYPE 0402
J 0
(-2100 2625);
DISPLAY 0.617021 (-2100 2625);
PAINT SKYBLUE (-2100 2625);
FORCEPROP 0 LAST GROUP NI_I210&RJ45
J 0
(-1994 2613);
DISPLAY 0.638298 (-1994 2613);
PAINT BROWN (-1994 2613);
DISPLAY BOTH (-1994 2613);
FORCEPROP 1 LASTPIN (-2500 2675) $PN 1
J 0
(-2488 2687);
DISPLAY 0.787234 (-2488 2687);
PAINT ORANGE (-2488 2687);
DISPLAY INVISIBLE (-2488 2687);
FORCEPROP 2 LAST CDS_LOCATION R9F1
J 0
(-2350 2675);
DISPLAY 0.617021 (-2350 2675);
PAINT AQUA (-2350 2675);
DISPLAY INVISIBLE (-2350 2675);
FORCEPROP 2 LAST CDS_LIB mstr_discrete
J 0
(-2400 2675);
PAINT ORANGE (-2400 2675);
DISPLAY INVISIBLE (-2400 2675);
FORCEPROP 1 LASTPIN (-2300 2675) $PN 2
J 0
(-2338 2687);
DISPLAY 0.787234 (-2338 2687);
PAINT ORANGE (-2338 2687);
DISPLAY INVISIBLE (-2338 2687);
FORCEPROP 1 LAST PATH I225
J 0
(-2450 2825);
DISPLAY 0.978723 (-2450 2825);
PAINT WHITE (-2450 2825);
DISPLAY INVISIBLE (-2450 2825);
FORCEPROP 2 LAST $SEC 1
J 0
(-2450 2875);
DISPLAY 0.680851 (-2450 2875);
PAINT MONO (-2450 2875);
DISPLAY INVISIBLE (-2450 2875);
FORCEPROP 2 LAST CDS_SEC 1
J 0
(-2450 2875);
DISPLAY 1.021277 (-2450 2875);
PAINT ORANGE (-2450 2875);
DISPLAY INVISIBLE (-2450 2875);
FORCEADD OFFPAGE..2
(-700 2675);
FORCEPROP 2 LAST $XR2 147 
J 0
(-271 2675);
DISPLAY 0.638298 (-271 2675);
PAINT MONO (-271 2675);
FORCEPROP 2 LAST $XR1 139 
J 0
(-391 2675);
DISPLAY 0.638298 (-391 2675);
PAINT MONO (-391 2675);
FORCEPROP 2 LAST $XR0 121 
J 0
(-511 2675);
DISPLAY 0.638298 (-511 2675);
PAINT MONO (-511 2675);
FORCEPROP 1 LAST COMMENT_BODY TRUE
J 0
(-745 2580);
DISPLAY 0.872340 (-745 2580);
PAINT GREEN (-745 2580);
DISPLAY INVISIBLE (-745 2580);
FORCEPROP 1 LAST OFFPAGE TRUE
J 0
(-375 2550);
DISPLAY 0.872340 (-375 2550);
PAINT GREEN (-375 2550);
DISPLAY INVISIBLE (-375 2550);
FORCEPROP 2 LAST PATH I226
J 0
(-650 2750);
DISPLAY 1.021277 (-650 2750);
PAINT ORANGE (-650 2750);
DISPLAY INVISIBLE (-650 2750);
FORCEPROP 2 LAST CDS_LIB mstr_standard
J 0
(-700 2675);
PAINT ORANGE (-700 2675);
DISPLAY INVISIBLE (-700 2675);
FORCEADD OFFPAGE..1
(-6050 2725);
FORCEPROP 2 LAST $XR1 139 
J 0
(-6422 2725);
DISPLAY 0.638298 (-6422 2725);
PAINT MONO (-6422 2725);
FORCEPROP 2 LAST $XR0 101 
J 0
(-6302 2725);
DISPLAY 0.638298 (-6302 2725);
PAINT MONO (-6302 2725);
FORCEPROP 2 LAST CDS_LIB mstr_standard
J 0
(-6050 2725);
PAINT ORANGE (-6050 2725);
DISPLAY INVISIBLE (-6050 2725);
FORCEPROP 2 LAST PATH I227
J 0
(-6000 2800);
DISPLAY 1.021277 (-6000 2800);
PAINT ORANGE (-6000 2800);
DISPLAY INVISIBLE (-6000 2800);
FORCEPROP 1 LAST OFFPAGE TRUE
J 0
(-5725 2600);
DISPLAY 0.872340 (-5725 2600);
PAINT GREEN (-5725 2600);
DISPLAY INVISIBLE (-5725 2600);
FORCEPROP 1 LAST COMMENT_BODY TRUE
J 0
(-5925 2625);
DISPLAY 0.872340 (-5925 2625);
PAINT GREEN (-5925 2625);
DISPLAY INVISIBLE (-5925 2625);
FORCEADD RES..1
(-2275 2525);
FORCEPROP 1 LAST WATTAGE 1/16W
J 0
(-2225 2575);
DISPLAY 0.638298 (-2225 2575);
PAINT SKYBLUE (-2225 2575);
FORCEPROP 1 LAST TOLERANCE 1.0%
J 2
(-2275 2575);
DISPLAY 0.617021 (-2275 2575);
PAINT SKYBLUE (-2275 2575);
FORCEPROP 1 LASTPIN (-2375 2525) $PN 1
J 0
(-2363 2537);
DISPLAY 0.617021 (-2363 2537);
PAINT ORANGE (-2363 2537);
FORCEPROP 1 LAST VALUE 22.1
J 2
(-2425 2575);
DISPLAY 0.617021 (-2425 2575);
PAINT SKYBLUE (-2425 2575);
FORCEPROP 1 LASTPIN (-2175 2525) $PN 2
J 0
(-2213 2537);
DISPLAY 0.617021 (-2213 2537);
PAINT ORANGE (-2213 2537);
FORCEPROP 1 LAST LOCATION R9E19
J 0
(-2675 2575);
DISPLAY 0.617021 (-2675 2575);
PAINT AQUA (-2675 2575);
FORCEPROP 1 LAST MATERIAL CHIP
J 2
(-1950 2575);
DISPLAY 0.617021 (-1950 2575);
PAINT SKYBLUE (-1950 2575);
FORCEPROP 1 LAST PART_NUMBER G21796-250
J 0
(-1900 2575);
DISPLAY 0.638298 (-1900 2575);
PAINT BLUE (-1900 2575);
FORCEPROP 0 LAST GROUP NI_I210&RJ45
J 0
(-1494 2588);
DISPLAY 0.638298 (-1494 2588);
PAINT BROWN (-1494 2588);
DISPLAY BOTH (-1494 2588);
FORCEPROP 1 LAST PACK_TYPE 0402
J 0
(-1600 2575);
DISPLAY 0.638298 (-1600 2575);
PAINT SKYBLUE (-1600 2575);
FORCEPROP 2 LAST CDS_LOCATION R9E19
J 0
(-2325 2475);
DISPLAY 0.617021 (-2325 2475);
PAINT AQUA (-2325 2475);
DISPLAY INVISIBLE (-2325 2475);
FORCEPROP 2 LAST CDS_LIB mstr_discrete
J 0
(-2275 2525);
PAINT ORANGE (-2275 2525);
DISPLAY INVISIBLE (-2275 2525);
FORCEPROP 2 LAST SEC_TYPE 0402
J 0
(-2325 2725);
DISPLAY 1.021277 (-2325 2725);
PAINT ORANGE (-2325 2725);
DISPLAY INVISIBLE (-2325 2725);
FORCEPROP 2 LAST SEC 1
J 0
(-2325 2725);
DISPLAY 0.680851 (-2325 2725);
PAINT MONO (-2325 2725);
DISPLAY INVISIBLE (-2325 2725);
FORCEPROP 1 LAST PATH I228
J 0
(-2325 2675);
DISPLAY 0.978723 (-2325 2675);
PAINT WHITE (-2325 2675);
DISPLAY INVISIBLE (-2325 2675);
FORCEPROP 2 LAST ROOM BMC
J 0
(-2000 2525);
DISPLAY 1.021277 (-2000 2525);
PAINT ORANGE (-2000 2525);
DISPLAY INVISIBLE (-2000 2525);
FORCEPROP 2 LAST BOM_COST SM_CONTROLLER
J 0
(-2000 2575);
DISPLAY 1.021277 (-2000 2575);
PAINT ORANGE (-2000 2575);
DISPLAY INVISIBLE (-2000 2575);
FORCEADD RES..1
(-1900 2450);
FORCEPROP 1 LAST LOCATION R9E17
J 0
(-2400 2475);
DISPLAY 0.617021 (-2400 2475);
PAINT AQUA (-2400 2475);
FORCEPROP 1 LASTPIN (-1800 2450) $PN 2
J 0
(-1838 2462);
DISPLAY 0.617021 (-1838 2462);
PAINT ORANGE (-1838 2462);
FORCEPROP 1 LASTPIN (-2000 2450) $PN 1
J 0
(-1988 2462);
DISPLAY 0.617021 (-1988 2462);
PAINT ORANGE (-1988 2462);
FORCEPROP 1 LAST PACK_TYPE 0402
J 0
(-1425 2500);
DISPLAY 0.638298 (-1425 2500);
PAINT SKYBLUE (-1425 2500);
FORCEPROP 1 LAST VALUE 22.1
J 2
(-2125 2475);
DISPLAY 0.617021 (-2125 2475);
PAINT SKYBLUE (-2125 2475);
FORCEPROP 1 LAST MATERIAL CHIP
J 2
(-1700 2500);
DISPLAY 0.617021 (-1700 2500);
PAINT SKYBLUE (-1700 2500);
FORCEPROP 1 LAST TOLERANCE 1.0%
J 2
(-2000 2475);
DISPLAY 0.617021 (-2000 2475);
PAINT SKYBLUE (-2000 2475);
FORCEPROP 1 LAST WATTAGE 1/16W
J 0
(-1975 2500);
DISPLAY 0.638298 (-1975 2500);
PAINT SKYBLUE (-1975 2500);
FORCEPROP 0 LAST GROUP NI_I210&RJ45
J 0
(-1994 2388);
DISPLAY 0.638298 (-1994 2388);
PAINT BROWN (-1994 2388);
DISPLAY BOTH (-1994 2388);
FORCEPROP 1 LAST PART_NUMBER G21796-250
J 0
(-1675 2500);
DISPLAY 0.638298 (-1675 2500);
PAINT BLUE (-1675 2500);
FORCEPROP 2 LAST CDS_LOCATION R9E17
J 0
(-1950 2400);
DISPLAY 0.617021 (-1950 2400);
PAINT AQUA (-1950 2400);
DISPLAY INVISIBLE (-1950 2400);
FORCEPROP 2 LAST CDS_LIB mstr_discrete
J 0
(-1900 2450);
PAINT ORANGE (-1900 2450);
DISPLAY INVISIBLE (-1900 2450);
FORCEPROP 1 LAST PATH I229
J 0
(-1950 2600);
DISPLAY 0.978723 (-1950 2600);
PAINT WHITE (-1950 2600);
DISPLAY INVISIBLE (-1950 2600);
FORCEPROP 2 LAST SEC 1
J 0
(-1950 2650);
DISPLAY 0.680851 (-1950 2650);
PAINT MONO (-1950 2650);
DISPLAY INVISIBLE (-1950 2650);
FORCEPROP 2 LAST SEC_TYPE 0402
J 0
(-1950 2650);
DISPLAY 1.021277 (-1950 2650);
PAINT ORANGE (-1950 2650);
DISPLAY INVISIBLE (-1950 2650);
FORCEPROP 2 LAST ROOM BMC
J 0
(-1625 2450);
DISPLAY 1.021277 (-1625 2450);
PAINT ORANGE (-1625 2450);
DISPLAY INVISIBLE (-1625 2450);
FORCEPROP 2 LAST BOM_COST SM_CONTROLLER
J 0
(-1625 2500);
DISPLAY 1.021277 (-1625 2500);
PAINT ORANGE (-1625 2500);
DISPLAY INVISIBLE (-1625 2500);
FORCEADD OFFPAGE..2
(-700 2525);
FORCEPROP 2 LAST $XR1 147 
J 0
(-391 2525);
DISPLAY 0.638298 (-391 2525);
PAINT MONO (-391 2525);
FORCEPROP 2 LAST $XR0 121 
J 0
(-511 2525);
DISPLAY 0.638298 (-511 2525);
PAINT MONO (-511 2525);
FORCEPROP 1 LAST COMMENT_BODY TRUE
J 0
(-745 2430);
DISPLAY 0.872340 (-745 2430);
PAINT GREEN (-745 2430);
DISPLAY INVISIBLE (-745 2430);
FORCEPROP 1 LAST OFFPAGE TRUE
J 0
(-375 2400);
DISPLAY 0.872340 (-375 2400);
PAINT GREEN (-375 2400);
DISPLAY INVISIBLE (-375 2400);
FORCEPROP 2 LAST PATH I230
J 0
(-650 2600);
DISPLAY 1.021277 (-650 2600);
PAINT ORANGE (-650 2600);
DISPLAY INVISIBLE (-650 2600);
FORCEPROP 2 LAST CDS_LIB mstr_standard
J 0
(-700 2525);
PAINT ORANGE (-700 2525);
DISPLAY INVISIBLE (-700 2525);
FORCEADD OFFPAGE..2
(-700 2475);
FORCEPROP 1 LAST COMMENT_BODY TRUE
J 0
(-745 2380);
DISPLAY 0.872340 (-745 2380);
PAINT GREEN (-745 2380);
DISPLAY INVISIBLE (-745 2380);
FORCEPROP 1 LAST OFFPAGE TRUE
J 0
(-375 2350);
DISPLAY 0.872340 (-375 2350);
PAINT GREEN (-375 2350);
DISPLAY INVISIBLE (-375 2350);
FORCEPROP 2 LAST PATH I231
J 0
(-525 2550);
DISPLAY 1.021277 (-525 2550);
PAINT ORANGE (-525 2550);
DISPLAY INVISIBLE (-525 2550);
FORCEPROP 2 LAST CDS_LIB mstr_standard
J 0
(-700 2475);
PAINT ORANGE (-700 2475);
DISPLAY INVISIBLE (-700 2475);
FORCEPROP 2 LAST $XR1 147 
R 1
J 0
(-750 2536);
DISPLAY 0.638298 (-750 2536);
PAINT MONO (-750 2536);
DISPLAY INVISIBLE (-750 2536);
FORCEPROP 2 LAST $XR0 121 
R 1
J 0
(-750 2536);
DISPLAY 0.638298 (-750 2536);
PAINT MONO (-750 2536);
DISPLAY INVISIBLE (-750 2536);
FORCEADD OFFPAGE..1
(-6050 2625);
FORCEPROP 2 LAST $XR1 125 
J 0
(-6422 2625);
DISPLAY 0.638298 (-6422 2625);
PAINT MONO (-6422 2625);
FORCEPROP 2 LAST $XR0 121 
J 0
(-6302 2625);
DISPLAY 0.638298 (-6302 2625);
PAINT MONO (-6302 2625);
FORCEPROP 2 LAST CDS_LIB mstr_standard
J 0
(-6050 2625);
PAINT MONO (-6050 2625);
DISPLAY INVISIBLE (-6050 2625);
FORCEPROP 2 LAST PATH I233
J 0
(-6000 2700);
DISPLAY 1.021277 (-6000 2700);
PAINT ORANGE (-6000 2700);
DISPLAY INVISIBLE (-6000 2700);
FORCEPROP 1 LAST OFFPAGE TRUE
J 0
(-5725 2500);
DISPLAY 0.872340 (-5725 2500);
PAINT GREEN (-5725 2500);
DISPLAY INVISIBLE (-5725 2500);
FORCEPROP 1 LAST COMMENT_BODY TRUE
J 0
(-5925 2525);
DISPLAY 0.872340 (-5925 2525);
PAINT GREEN (-5925 2525);
DISPLAY INVISIBLE (-5925 2525);
FORCEADD RES..1
(-2075 2725);
FORCEPROP 0 LAST GROUP NI_I210&RJ45
J 0
(-2069 2763);
DISPLAY 0.638298 (-2069 2763);
PAINT BROWN (-2069 2763);
DISPLAY BOTH (-2069 2763);
FORCEPROP 1 LASTPIN (-1975 2725) $PN 2
J 0
(-2013 2737);
DISPLAY 0.617021 (-2013 2737);
PAINT ORANGE (-2013 2737);
FORCEPROP 1 LAST WATTAGE 1/16W
J 2
(-2425 2775);
DISPLAY 0.617021 (-2425 2775);
PAINT SKYBLUE (-2425 2775);
FORCEPROP 1 LAST VALUE 33.2
J 2
(-2325 2775);
DISPLAY 0.617021 (-2325 2775);
PAINT SKYBLUE (-2325 2775);
FORCEPROP 1 LAST LOCATION R9E16
J 0
(-1875 2675);
DISPLAY 0.617021 (-1875 2675);
PAINT AQUA (-1875 2675);
FORCEPROP 1 LAST MATERIAL CHIP
J 0
(-2300 2775);
DISPLAY 0.617021 (-2300 2775);
PAINT SKYBLUE (-2300 2775);
FORCEPROP 1 LAST PACK_TYPE 0402
J 0
(-2175 2775);
DISPLAY 0.617021 (-2175 2775);
PAINT SKYBLUE (-2175 2775);
FORCEPROP 1 LASTPIN (-2175 2725) $PN 1
J 0
(-2163 2737);
DISPLAY 0.617021 (-2163 2737);
PAINT ORANGE (-2163 2737);
FORCEPROP 1 LAST TOLERANCE 1%
J 0
(-2025 2675);
DISPLAY 0.617021 (-2025 2675);
PAINT SKYBLUE (-2025 2675);
FORCEPROP 1 LAST PART_NUMBER G21796-074
J 0
(-1975 2725);
DISPLAY 0.617021 (-1975 2725);
PAINT BLUE (-1975 2725);
FORCEPROP 2 LAST CDS_LIB mstr_discrete
J 0
(-2075 2725);
PAINT ORANGE (-2075 2725);
DISPLAY INVISIBLE (-2075 2725);
FORCEPROP 1 LAST PATH I235
J 0
(-2125 2875);
DISPLAY 0.978723 (-2125 2875);
PAINT WHITE (-2125 2875);
DISPLAY INVISIBLE (-2125 2875);
FORCEPROP 2 LAST SEC 1
J 0
(-2125 2925);
DISPLAY 0.680851 (-2125 2925);
PAINT MONO (-2125 2925);
DISPLAY INVISIBLE (-2125 2925);
FORCEPROP 2 LAST SEC_TYPE 0402
J 0
(-2125 2925);
DISPLAY 1.021277 (-2125 2925);
PAINT ORANGE (-2125 2925);
DISPLAY INVISIBLE (-2125 2925);
FORCEPROP 2 LAST CDS_LOCATION R9E16
J 0
(-1875 2675);
DISPLAY 0.617021 (-1875 2675);
PAINT AQUA (-1875 2675);
DISPLAY INVISIBLE (-1875 2675);
FORCEPROP 0 LAST ROOM SB
J 0
(-2025 2825);
DISPLAY 1.021277 (-2025 2825);
PAINT ORANGE (-2025 2825);
DISPLAY INVISIBLE (-2025 2825);
FORCEADD OFFPAGE..2
(-700 2725);
FORCEPROP 2 LAST $XR0 121 
J 0
(-511 2725);
DISPLAY 0.638298 (-511 2725);
PAINT MONO (-511 2725);
FORCEPROP 1 LAST COMMENT_BODY TRUE
J 0
(-745 2630);
DISPLAY 0.872340 (-745 2630);
PAINT GREEN (-745 2630);
DISPLAY INVISIBLE (-745 2630);
FORCEPROP 1 LAST OFFPAGE TRUE
J 0
(-375 2600);
DISPLAY 0.872340 (-375 2600);
PAINT GREEN (-375 2600);
DISPLAY INVISIBLE (-375 2600);
FORCEPROP 2 LAST PATH I236
J 0
(-525 2800);
DISPLAY 1.021277 (-525 2800);
PAINT ORANGE (-525 2800);
DISPLAY INVISIBLE (-525 2800);
FORCEPROP 2 LAST CDS_LIB mstr_standard
J 0
(-700 2725);
PAINT ORANGE (-700 2725);
DISPLAY INVISIBLE (-700 2725);
FORCEADD RES..1
(-5600 4025);
FORCEPROP 1 LAST PART_NUMBER G22178-002
J 0
(-5650 4125);
DISPLAY 0.617021 (-5650 4125);
PAINT BLUE (-5650 4125);
FORCEPROP 1 LAST WATTAGE 1/10W
J 2
(-5375 4225);
DISPLAY 0.617021 (-5375 4225);
PAINT SKYBLUE (-5375 4225);
FORCEPROP 1 LASTPIN (-5500 4025) $PN 2
J 0
(-5538 4037);
DISPLAY 0.617021 (-5538 4037);
PAINT ORANGE (-5538 4037);
FORCEPROP 1 LAST MATERIAL CHIP
J 0
(-5650 4175);
DISPLAY 0.617021 (-5650 4175);
PAINT SKYBLUE (-5650 4175);
FORCEPROP 1 LAST TOLERANCE 5.0%
J 0
(-5650 4225);
DISPLAY 0.617021 (-5650 4225);
PAINT SKYBLUE (-5650 4225);
FORCEPROP 1 LAST VALUE 0
J 2
(-5450 4275);
DISPLAY 0.617021 (-5450 4275);
PAINT SKYBLUE (-5450 4275);
FORCEPROP 1 LAST LOCATION R1R15
J 0
(-5650 4275);
DISPLAY 0.617021 (-5650 4275);
PAINT AQUA (-5650 4275);
FORCEPROP 1 LAST PACK_TYPE 0603
J 0
(-5650 4075);
DISPLAY 0.617021 (-5650 4075);
PAINT SKYBLUE (-5650 4075);
FORCEPROP 0 LAST GROUP NI_I210&RJ45
J 0
(-5444 3988);
DISPLAY 0.638298 (-5444 3988);
PAINT BROWN (-5444 3988);
DISPLAY BOTH (-5444 3988);
FORCEPROP 1 LASTPIN (-5700 4025) $PN 1
J 0
(-5688 4037);
DISPLAY 0.617021 (-5688 4037);
PAINT ORANGE (-5688 4037);
FORCEPROP 2 LAST CDS_LIB mstr_discrete
J 0
(-5600 4025);
PAINT ORANGE (-5600 4025);
DISPLAY INVISIBLE (-5600 4025);
FORCEPROP 2 LAST CDS_LOCATION R1R15
J 0
(-5675 4075);
DISPLAY 0.617021 (-5675 4075);
PAINT AQUA (-5675 4075);
DISPLAY INVISIBLE (-5675 4075);
FORCEPROP 1 LAST PATH I237
J 0
(-5650 4175);
DISPLAY 0.978723 (-5650 4175);
PAINT WHITE (-5650 4175);
DISPLAY INVISIBLE (-5650 4175);
FORCEPROP 2 LAST SEC 1
J 0
(-5650 4225);
DISPLAY 0.680851 (-5650 4225);
PAINT MONO (-5650 4225);
DISPLAY INVISIBLE (-5650 4225);
FORCEPROP 2 LAST SEC_TYPE 0603
J 0
(-5650 4225);
DISPLAY 1.021277 (-5650 4225);
PAINT ORANGE (-5650 4225);
DISPLAY INVISIBLE (-5650 4225);
FORCEPROP 0 LAST ROOM NIC_SPRV
J 0
(-5500 4150);
DISPLAY 1.021277 (-5500 4150);
PAINT ORANGE (-5500 4150);
DISPLAY INVISIBLE (-5500 4150);
FORCEPROP 0 LAST BOM_COST NT_GBE_BASE
J 0
(-5500 4250);
DISPLAY 1.021277 (-5500 4250);
PAINT ORANGE (-5500 4250);
DISPLAY INVISIBLE (-5500 4250);
FORCEADD RES..1
(-5800 3875);
FORCEPROP 0 LAST GROUP NI_I210&RJ45
J 0
(-5469 3838);
DISPLAY 0.638298 (-5469 3838);
PAINT BROWN (-5469 3838);
DISPLAY BOTH (-5469 3838);
FORCEPROP 1 LASTPIN (-5700 3875) $PN 2
J 0
(-5738 3887);
DISPLAY 0.617021 (-5738 3887);
PAINT ORANGE (-5738 3887);
FORCEPROP 1 LASTPIN (-5900 3875) $PN 1
J 0
(-5888 3887);
DISPLAY 0.617021 (-5888 3887);
PAINT ORANGE (-5888 3887);
FORCEPROP 1 LAST MATERIAL CHIP
J 0
(-6000 3925);
DISPLAY 0.617021 (-6000 3925);
PAINT SKYBLUE (-6000 3925);
FORCEPROP 1 LAST PACK_TYPE 0603
J 0
(-5600 3925);
DISPLAY 0.617021 (-5600 3925);
PAINT SKYBLUE (-5600 3925);
FORCEPROP 1 LAST WATTAGE 1/10W
J 2
(-5500 3975);
DISPLAY 0.617021 (-5500 3975);
PAINT SKYBLUE (-5500 3975);
FORCEPROP 1 LAST LOCATION R1T32
J 0
(-6000 3975);
DISPLAY 0.617021 (-6000 3975);
PAINT AQUA (-6000 3975);
FORCEPROP 1 LAST PART_NUMBER G22178-002
J 0
(-5850 3925);
DISPLAY 0.617021 (-5850 3925);
PAINT BLUE (-5850 3925);
FORCEPROP 1 LAST VALUE 0
J 2
(-5800 3975);
DISPLAY 0.617021 (-5800 3975);
PAINT SKYBLUE (-5800 3975);
FORCEPROP 1 LAST TOLERANCE 5.0%
J 0
(-5750 3975);
DISPLAY 0.617021 (-5750 3975);
PAINT SKYBLUE (-5750 3975);
FORCEPROP 1 LAST PATH I238
J 0
(-5850 4025);
DISPLAY 0.978723 (-5850 4025);
PAINT WHITE (-5850 4025);
DISPLAY INVISIBLE (-5850 4025);
FORCEPROP 2 LAST CDS_LIB mstr_discrete
J 0
(-5800 3875);
PAINT ORANGE (-5800 3875);
DISPLAY INVISIBLE (-5800 3875);
FORCEPROP 2 LAST CDS_LOCATION R1T32
J 0
(-5700 3900);
DISPLAY 0.617021 (-5700 3900);
PAINT AQUA (-5700 3900);
DISPLAY INVISIBLE (-5700 3900);
FORCEPROP 0 LAST ROOM NIC_SPRV
J 0
(-5700 4000);
DISPLAY 1.021277 (-5700 4000);
PAINT ORANGE (-5700 4000);
DISPLAY INVISIBLE (-5700 4000);
FORCEPROP 2 LAST SEC 1
J 0
(-5850 4075);
DISPLAY 0.680851 (-5850 4075);
PAINT MONO (-5850 4075);
DISPLAY INVISIBLE (-5850 4075);
FORCEPROP 2 LAST SEC_TYPE 0603
J 0
(-5850 4075);
DISPLAY 1.021277 (-5850 4075);
PAINT ORANGE (-5850 4075);
DISPLAY INVISIBLE (-5850 4075);
FORCEPROP 0 LAST BOM_COST NT_GBE_BASE
J 0
(-5700 4100);
DISPLAY 1.021277 (-5700 4100);
PAINT ORANGE (-5700 4100);
DISPLAY INVISIBLE (-5700 4100);
FORCEADD RES..1
(-5600 3525);
FORCEPROP 1 LAST TOLERANCE 5.0%
J 0
(-5550 3575);
DISPLAY 0.617021 (-5550 3575);
PAINT SKYBLUE (-5550 3575);
FORCEPROP 1 LASTPIN (-5500 3525) $PN 2
J 0
(-5538 3537);
DISPLAY 0.617021 (-5538 3537);
PAINT ORANGE (-5538 3537);
FORCEPROP 1 LAST PART_NUMBER G22178-002
J 0
(-5700 3475);
DISPLAY 0.617021 (-5700 3475);
PAINT BLUE (-5700 3475);
FORCEPROP 1 LAST LOCATION R1T34
J 0
(-5850 3575);
DISPLAY 0.617021 (-5850 3575);
PAINT AQUA (-5850 3575);
FORCEPROP 1 LASTPIN (-5700 3525) $PN 1
J 0
(-5688 3537);
DISPLAY 0.617021 (-5688 3537);
PAINT ORANGE (-5688 3537);
FORCEPROP 1 LAST VALUE 0
J 2
(-5625 3575);
DISPLAY 0.617021 (-5625 3575);
PAINT SKYBLUE (-5625 3575);
FORCEPROP 1 LAST WATTAGE 1/10W
J 0
(-5425 3575);
DISPLAY 0.617021 (-5425 3575);
PAINT SKYBLUE (-5425 3575);
FORCEPROP 1 LAST MATERIAL CHIP
J 0
(-5875 3475);
DISPLAY 0.617021 (-5875 3475);
PAINT SKYBLUE (-5875 3475);
FORCEPROP 1 LAST PACK_TYPE 0603
J 0
(-5400 3475);
DISPLAY 0.617021 (-5400 3475);
PAINT SKYBLUE (-5400 3475);
FORCEPROP 0 LAST GROUP NI_I210&RJ45
J 0
(-5844 3438);
DISPLAY 0.638298 (-5844 3438);
PAINT BROWN (-5844 3438);
DISPLAY BOTH (-5844 3438);
FORCEPROP 1 LAST PATH I239
J 0
(-5650 3675);
DISPLAY 0.978723 (-5650 3675);
PAINT WHITE (-5650 3675);
DISPLAY INVISIBLE (-5650 3675);
FORCEPROP 2 LAST SEC 1
J 0
(-5650 3725);
DISPLAY 0.680851 (-5650 3725);
PAINT MONO (-5650 3725);
DISPLAY INVISIBLE (-5650 3725);
FORCEPROP 2 LAST SEC_TYPE 0603
J 0
(-5650 3725);
DISPLAY 1.021277 (-5650 3725);
PAINT ORANGE (-5650 3725);
DISPLAY INVISIBLE (-5650 3725);
FORCEPROP 2 LAST CDS_LIB mstr_discrete
J 0
(-5600 3525);
PAINT ORANGE (-5600 3525);
DISPLAY INVISIBLE (-5600 3525);
FORCEPROP 2 LAST CDS_LOCATION R1T34
J 0
(-5500 3550);
DISPLAY 0.617021 (-5500 3550);
PAINT AQUA (-5500 3550);
DISPLAY INVISIBLE (-5500 3550);
FORCEPROP 0 LAST ROOM NIC_SPRV
J 0
(-5500 3650);
DISPLAY 1.021277 (-5500 3650);
PAINT ORANGE (-5500 3650);
DISPLAY INVISIBLE (-5500 3650);
FORCEPROP 0 LAST BOM_COST NT_GBE_BASE
J 0
(-5500 3750);
DISPLAY 1.021277 (-5500 3750);
PAINT ORANGE (-5500 3750);
DISPLAY INVISIBLE (-5500 3750);
FORCEADD RES..1
(-5800 3725);
FORCEPROP 1 LAST LOCATION R1T33
J 0
(-6000 3825);
DISPLAY 0.617021 (-6000 3825);
PAINT AQUA (-6000 3825);
FORCEPROP 1 LAST PACK_TYPE 0603
J 0
(-5425 3775);
DISPLAY 0.617021 (-5425 3775);
PAINT SKYBLUE (-5425 3775);
FORCEPROP 1 LASTPIN (-5700 3725) $PN 2
J 0
(-5738 3737);
DISPLAY 0.617021 (-5738 3737);
PAINT ORANGE (-5738 3737);
FORCEPROP 1 LASTPIN (-5900 3725) $PN 1
J 0
(-5888 3737);
DISPLAY 0.617021 (-5888 3737);
PAINT ORANGE (-5888 3737);
FORCEPROP 1 LAST MATERIAL EMPTY
J 0
(-6000 3775);
DISPLAY 0.617021 (-6000 3775);
PAINT RED (-6000 3775);
FORCEPROP 1 LAST TOLERANCE 5.0%
J 0
(-5750 3825);
DISPLAY 0.617021 (-5750 3825);
PAINT SKYBLUE (-5750 3825);
FORCEPROP 0 LAST GROUP NI_I210&RJ45
J 0
(-5694 3638);
DISPLAY 0.638298 (-5694 3638);
PAINT BROWN (-5694 3638);
DISPLAY BOTH (-5694 3638);
FORCEPROP 1 LAST PART_NUMBER G22178-002
J 0
(-5675 3775);
DISPLAY 0.617021 (-5675 3775);
PAINT BLUE (-5675 3775);
FORCEPROP 1 LAST WATTAGE 1/10W
J 2
(-5500 3825);
DISPLAY 0.617021 (-5500 3825);
PAINT SKYBLUE (-5500 3825);
FORCEPROP 1 LAST VALUE 0
J 2
(-5800 3825);
DISPLAY 0.617021 (-5800 3825);
PAINT SKYBLUE (-5800 3825);
FORCEPROP 0 LAST BOM_COST NT_GBE_BASE
J 0
(-5700 3950);
DISPLAY 1.021277 (-5700 3950);
PAINT ORANGE (-5700 3950);
DISPLAY INVISIBLE (-5700 3950);
FORCEPROP 0 LAST ROOM NIC_SPRV
J 0
(-5700 3850);
DISPLAY 1.021277 (-5700 3850);
PAINT ORANGE (-5700 3850);
DISPLAY INVISIBLE (-5700 3850);
FORCEPROP 2 LAST SEC_TYPE 0603
J 0
(-5850 3925);
DISPLAY 1.021277 (-5850 3925);
PAINT ORANGE (-5850 3925);
DISPLAY INVISIBLE (-5850 3925);
FORCEPROP 2 LAST SEC 1
J 0
(-5850 3925);
DISPLAY 0.680851 (-5850 3925);
PAINT MONO (-5850 3925);
DISPLAY INVISIBLE (-5850 3925);
FORCEPROP 1 LAST PATH I240
J 0
(-5850 3875);
DISPLAY 0.978723 (-5850 3875);
PAINT WHITE (-5850 3875);
DISPLAY INVISIBLE (-5850 3875);
FORCEPROP 2 LAST CDS_LOCATION R1T33
J 0
(-5700 3750);
DISPLAY 0.617021 (-5700 3750);
PAINT AQUA (-5700 3750);
DISPLAY INVISIBLE (-5700 3750);
FORCEPROP 2 LAST CDS_LIB mstr_discrete
J 0
(-5800 3725);
PAINT ORANGE (-5800 3725);
DISPLAY INVISIBLE (-5800 3725);
FORCEADD CAP_A..1
(-1925 875);
FORCEPROP 0 LAST GROUP NI_I210&RJ45
J 0
(-1869 613);
DISPLAY 0.638298 (-1869 613);
PAINT BROWN (-1869 613);
DISPLAY BOTH (-1869 613);
FORCEPROP 1 LASTPIN (-1925 775) $PN 2
J 0
(-1915 755);
DISPLAY 0.617021 (-1915 755);
PAINT ORANGE (-1915 755);
FORCEPROP 1 LASTPIN (-1925 975) $PN 1
J 0
(-1915 955);
DISPLAY 0.617021 (-1915 955);
PAINT ORANGE (-1915 955);
FORCEPROP 1 LAST LOCATION C9E12
J 0
(-1875 975);
DISPLAY 0.617021 (-1875 975);
PAINT AQUA (-1875 975);
FORCEPROP 1 LAST MATERIAL EMPTY
J 0
(-1875 775);
DISPLAY 0.617021 (-1875 775);
PAINT RED (-1875 775);
FORCEPROP 1 LAST TOLERANCE 20%
J 0
(-1875 825);
DISPLAY 0.617021 (-1875 825);
PAINT SKYBLUE (-1875 825);
FORCEPROP 1 LAST PART_NUMBER E15431-004
J 0
(-1875 725);
DISPLAY 0.617021 (-1875 725);
PAINT BLUE (-1875 725);
FORCEPROP 1 LAST PACK_TYPE 0603V
J 0
(-1875 675);
DISPLAY 0.617021 (-1875 675);
PAINT SKYBLUE (-1875 675);
FORCEPROP 1 LAST VALUE 22.0UF
J 0
(-1875 925);
DISPLAY 0.617021 (-1875 925);
PAINT SKYBLUE (-1875 925);
FORCEPROP 1 LAST VOLTAGE 4V
J 0
(-1875 875);
DISPLAY 0.617021 (-1875 875);
PAINT SKYBLUE (-1875 875);
FORCEPROP 2 LAST CDS_LIB dev_discrete
J 0
(-1925 875);
PAINT ORANGE (-1925 875);
DISPLAY INVISIBLE (-1925 875);
FORCEPROP 2 LAST BOM_COST NT_GBE_BASE
J 0
(-1875 1075);
DISPLAY 1.021277 (-1875 1075);
PAINT ORANGE (-1875 1075);
DISPLAY INVISIBLE (-1875 1075);
FORCEPROP 2 LAST SEC 1
J 0
(-1875 1075);
DISPLAY 0.680851 (-1875 1075);
PAINT MONO (-1875 1075);
DISPLAY INVISIBLE (-1875 1075);
FORCEPROP 2 LAST SEC_TYPE 0603V
J 0
(-1875 1075);
DISPLAY 1.021277 (-1875 1075);
PAINT ORANGE (-1875 1075);
DISPLAY INVISIBLE (-1875 1075);
FORCEPROP 1 LAST PATH I241
J 0
(-1875 1025);
DISPLAY 0.978723 (-1875 1025);
PAINT WHITE (-1875 1025);
DISPLAY INVISIBLE (-1875 1025);
FORCEPROP 2 LAST ROOM NIC_SPRV
J 0
(-1875 1025);
DISPLAY 1.021277 (-1875 1025);
PAINT ORANGE (-1875 1025);
DISPLAY INVISIBLE (-1875 1025);
FORCEADD GND..1
(-6100 525);
FORCEPROP 3 LASTPIN (-6100 575) SIG_NAME GND\g
J 0
(-6090 585);
DISPLAY 0.659574 (-6090 585);
PAINT MONO (-6090 585);
DISPLAY INVISIBLE (-6090 585);
FORCEPROP 2 LAST CDS_LIB mstr_symbols
J 0
(-6100 525);
PAINT MONO (-6100 525);
DISPLAY INVISIBLE (-6100 525);
FORCEPROP 2 LAST BOM_COST PVPP_KLM_VR
J 0
(-6950 600);
DISPLAY 1.042553 (-6950 600);
PAINT WHITE (-6950 600);
DISPLAY INVISIBLE (-6950 600);
FORCEPROP 2 LAST ROOM PVPP_KLM_VR
J 0
(-6675 600);
DISPLAY 1.042553 (-6675 600);
PAINT GREEN (-6675 600);
DISPLAY INVISIBLE (-6675 600);
FORCEPROP 1 LAST BODY_TYPE PLUMBING
J 0
(-6145 482);
DISPLAY 0.340426 (-6145 482);
PAINT GREEN (-6145 482);
DISPLAY INVISIBLE (-6145 482);
FORCEPROP 1 LAST VOLTAGE 0
J 0
(-6100 525);
PAINT SKYBLUE (-6100 525);
DISPLAY INVISIBLE (-6100 525);
FORCEPROP 1 LAST SIZE 1B
J 0
(-6025 475);
DISPLAY 0.872340 (-6025 475);
PAINT GREEN (-6025 475);
DISPLAY INVISIBLE (-6025 475);
FORCEPROP 1 LAST HDL_POWER GND
J 0
(-6100 675);
DISPLAY 0.872340 (-6100 675);
PAINT GREEN (-6100 675);
DISPLAY INVISIBLE (-6100 675);
FORCEPROP 1 LAST PATH I243
J 0
(-6025 525);
DISPLAY 0.872340 (-6025 525);
PAINT AQUA (-6025 525);
DISPLAY INVISIBLE (-6025 525);
FORCEADD SC22U16V5MX-4-GP..1
(-5800 825);
FORCEPROP 2 LASTPIN (-5800 750) $PN 2
R 1
J 2
(-5810 740);
DISPLAY 0.808511 (-5810 740);
PAINT ORANGE (-5810 740);
FORCEPROP 2 LASTPIN (-5800 900) $PN 1
R 1
J 0
(-5810 910);
DISPLAY 0.808511 (-5810 910);
PAINT ORANGE (-5810 910);
FORCEPROP 2 LAST TOLERANCE 20%
J 0
(-5700 850);
DISPLAY 0.638298 (-5700 850);
PAINT GREEN (-5700 850);
FORCEPROP 2 LAST TYPE X6S
J 0
(-5700 750);
DISPLAY 0.638298 (-5700 750);
PAINT GREEN (-5700 750);
FORCEPROP 2 LAST RATED 16V
J 0
(-5700 800);
DISPLAY 0.638298 (-5700 800);
PAINT GREEN (-5700 800);
FORCEPROP 2 LAST ATTRIBUTE 22UF
J 0
(-5700 900);
DISPLAY 0.638298 (-5700 900);
PAINT GREEN (-5700 900);
FORCEPROP 1 LAST LOCATION C22W34
J 0
(-5700 960);
DISPLAY 0.617021 (-5700 960);
PAINT GREEN (-5700 960);
FORCEPROP 1 LAST VALUE SC22U16V5MX-4-GP
R 1
J 0
(-5725 595);
DISPLAY 0.617021 (-5725 595);
PAINT GREEN (-5725 595);
FORCEPROP 0 LAST POP NOPOP
J 0
(-5700 650);
DISPLAY 0.638298 (-5700 650);
PAINT RED (-5700 650);
FORCEPROP 2 LAST PACK_SIZE 0805
J 0
(-5700 700);
DISPLAY 0.638298 (-5700 700);
PAINT GREEN (-5700 700);
FORCEPROP 0 LAST GROUP NI_I210&RJ45
J 0
(-5794 513);
DISPLAY 0.638298 (-5794 513);
PAINT BROWN (-5794 513);
DISPLAY BOTH (-5794 513);
FORCEPROP 1 LAST PATH I244
J 0
(-5800 825);
DISPLAY 0.617021 (-5800 825);
PAINT GREEN (-5800 825);
DISPLAY INVISIBLE (-5800 825);
FORCEPROP 1 LAST PACK_TYPE SMD-BCG5
J 0
(-5800 825);
DISPLAY 0.617021 (-5800 825);
PAINT GREEN (-5800 825);
DISPLAY INVISIBLE (-5800 825);
FORCEPROP 2 LAST SEC 1
J 0
(-5775 900);
DISPLAY 0.680851 (-5775 900);
PAINT MONO (-5775 900);
DISPLAY INVISIBLE (-5775 900);
FORCEPROP 2 LAST SEC_TYPE SMD-BCG5
J 0
(-5775 900);
DISPLAY 1.021277 (-5775 900);
PAINT ORANGE (-5775 900);
DISPLAY INVISIBLE (-5775 900);
FORCEPROP 1 LAST PART_NUMBER 078.22611.0811
J 0
(-5800 825);
DISPLAY 0.617021 (-5800 825);
PAINT GREEN (-5800 825);
DISPLAY INVISIBLE (-5800 825);
FORCEPROP 2 LAST CDS_LIB w_hdl
J 0
(-5800 825);
PAINT MONO (-5800 825);
DISPLAY INVISIBLE (-5800 825);
FORCEPROP 1 LAST CDS_LMAN_SYM_OUTLINE -50,25,50,-25
J 0
(-5800 825);
DISPLAY 0.468085 (-5800 825);
PAINT GREEN (-5800 825);
DISPLAY INVISIBLE (-5800 825);
FORCEADD SC22U16V5MX-4-GP..1
(-6100 825);
FORCEPROP 1 LAST LOCATION C9F2
J 0
(-6000 960);
DISPLAY 0.617021 (-6000 960);
PAINT GREEN (-6000 960);
FORCEPROP 0 LAST POP NOPOP
J 0
(-6000 650);
DISPLAY 0.638298 (-6000 650);
PAINT RED (-6000 650);
FORCEPROP 2 LAST RATED 16V
J 0
(-6000 800);
DISPLAY 0.638298 (-6000 800);
PAINT GREEN (-6000 800);
FORCEPROP 2 LASTPIN (-6100 900) $PN 1
R 1
J 0
(-6110 910);
DISPLAY 0.808511 (-6110 910);
PAINT ORANGE (-6110 910);
FORCEPROP 2 LASTPIN (-6100 750) $PN 2
R 1
J 2
(-6110 740);
DISPLAY 0.808511 (-6110 740);
PAINT ORANGE (-6110 740);
FORCEPROP 2 LAST PACK_SIZE 0805
J 0
(-6000 700);
DISPLAY 0.638298 (-6000 700);
PAINT GREEN (-6000 700);
FORCEPROP 2 LAST TYPE X6S
J 0
(-6000 750);
DISPLAY 0.638298 (-6000 750);
PAINT GREEN (-6000 750);
FORCEPROP 2 LAST TOLERANCE 20%
J 0
(-6000 850);
DISPLAY 0.638298 (-6000 850);
PAINT GREEN (-6000 850);
FORCEPROP 1 LAST VALUE SC22U16V5MX-4-GP
R 1
J 0
(-6025 595);
DISPLAY 0.617021 (-6025 595);
PAINT GREEN (-6025 595);
FORCEPROP 2 LAST ATTRIBUTE 22UF
J 0
(-6000 900);
DISPLAY 0.638298 (-6000 900);
PAINT GREEN (-6000 900);
FORCEPROP 0 LAST GROUP NI_I210&RJ45
J 0
(-6044 563);
DISPLAY 0.638298 (-6044 563);
PAINT BROWN (-6044 563);
DISPLAY BOTH (-6044 563);
FORCEPROP 1 LAST PATH I245
J 0
(-6100 825);
DISPLAY 0.617021 (-6100 825);
PAINT GREEN (-6100 825);
DISPLAY INVISIBLE (-6100 825);
FORCEPROP 1 LAST CDS_LMAN_SYM_OUTLINE -50,25,50,-25
J 0
(-6100 825);
DISPLAY 0.468085 (-6100 825);
PAINT GREEN (-6100 825);
DISPLAY INVISIBLE (-6100 825);
FORCEPROP 2 LAST CDS_LIB w_hdl
J 0
(-6100 825);
PAINT MONO (-6100 825);
DISPLAY INVISIBLE (-6100 825);
FORCEPROP 1 LAST PART_NUMBER 078.22611.0811
J 0
(-6100 825);
DISPLAY 0.617021 (-6100 825);
PAINT GREEN (-6100 825);
DISPLAY INVISIBLE (-6100 825);
FORCEPROP 2 LAST SEC_TYPE SMD-BCG5
J 0
(-6075 900);
DISPLAY 1.021277 (-6075 900);
PAINT ORANGE (-6075 900);
DISPLAY INVISIBLE (-6075 900);
FORCEPROP 2 LAST SEC 1
J 0
(-6075 900);
DISPLAY 0.680851 (-6075 900);
PAINT MONO (-6075 900);
DISPLAY INVISIBLE (-6075 900);
FORCEPROP 1 LAST PACK_TYPE SMD-BCG5
J 0
(-6100 825);
DISPLAY 0.617021 (-6100 825);
PAINT GREEN (-6100 825);
DISPLAY INVISIBLE (-6100 825);
FORCEADD SC22U16V5MX-4-GP..1
(-3700 800);
FORCEPROP 2 LAST PACK_SIZE 0805
J 0
(-3600 700);
DISPLAY 0.638298 (-3600 700);
PAINT GREEN (-3600 700);
FORCEPROP 1 LAST LOCATION C22W35
J 0
(-3600 960);
DISPLAY 0.617021 (-3600 960);
PAINT GREEN (-3600 960);
FORCEPROP 2 LASTPIN (-3700 875) $PN 1
R 1
J 0
(-3710 885);
DISPLAY 0.808511 (-3710 885);
PAINT ORANGE (-3710 885);
FORCEPROP 2 LAST RATED 16V
J 0
(-3600 800);
DISPLAY 0.638298 (-3600 800);
PAINT GREEN (-3600 800);
FORCEPROP 2 LAST TOLERANCE 20%
J 0
(-3600 850);
DISPLAY 0.638298 (-3600 850);
PAINT GREEN (-3600 850);
FORCEPROP 2 LAST ATTRIBUTE 22UF
J 0
(-3600 900);
DISPLAY 0.638298 (-3600 900);
PAINT GREEN (-3600 900);
FORCEPROP 2 LAST TYPE X6S
J 0
(-3600 750);
DISPLAY 0.638298 (-3600 750);
PAINT GREEN (-3600 750);
FORCEPROP 2 LASTPIN (-3700 725) $PN 2
R 1
J 2
(-3710 715);
DISPLAY 0.808511 (-3710 715);
PAINT ORANGE (-3710 715);
FORCEPROP 0 LAST POP NOPOP
J 0
(-3600 650);
DISPLAY 0.638298 (-3600 650);
PAINT RED (-3600 650);
FORCEPROP 1 LAST VALUE SC22U16V5MX-4-GP
R 1
J 0
(-3625 595);
DISPLAY 0.617021 (-3625 595);
PAINT GREEN (-3625 595);
FORCEPROP 0 LAST GROUP NI_I210&RJ45
J 0
(-3644 513);
DISPLAY 0.638298 (-3644 513);
PAINT BROWN (-3644 513);
DISPLAY BOTH (-3644 513);
FORCEPROP 1 LAST PATH I246
J 0
(-3700 800);
DISPLAY 0.617021 (-3700 800);
PAINT GREEN (-3700 800);
DISPLAY INVISIBLE (-3700 800);
FORCEPROP 1 LAST CDS_LMAN_SYM_OUTLINE -50,25,50,-25
J 0
(-3700 800);
DISPLAY 0.468085 (-3700 800);
PAINT GREEN (-3700 800);
DISPLAY INVISIBLE (-3700 800);
FORCEPROP 2 LAST CDS_LIB w_hdl
J 0
(-3700 800);
PAINT MONO (-3700 800);
DISPLAY INVISIBLE (-3700 800);
FORCEPROP 1 LAST PART_NUMBER 078.22611.0811
J 0
(-3700 800);
DISPLAY 0.617021 (-3700 800);
PAINT GREEN (-3700 800);
DISPLAY INVISIBLE (-3700 800);
FORCEPROP 2 LAST SEC_TYPE SMD-BCG5
J 0
(-3675 875);
DISPLAY 1.021277 (-3675 875);
PAINT ORANGE (-3675 875);
DISPLAY INVISIBLE (-3675 875);
FORCEPROP 2 LAST SEC 1
J 0
(-3675 875);
DISPLAY 0.680851 (-3675 875);
PAINT MONO (-3675 875);
DISPLAY INVISIBLE (-3675 875);
FORCEPROP 1 LAST PACK_TYPE SMD-BCG5
J 0
(-3700 800);
DISPLAY 0.617021 (-3700 800);
PAINT GREEN (-3700 800);
DISPLAY INVISIBLE (-3700 800);
FORCEADD GND..1
(-4000 525);
FORCEPROP 3 LASTPIN (-4000 575) SIG_NAME GND\g
J 0
(-3990 585);
DISPLAY 0.659574 (-3990 585);
PAINT MONO (-3990 585);
DISPLAY INVISIBLE (-3990 585);
FORCEPROP 1 LAST HDL_POWER GND
J 0
(-4000 675);
DISPLAY 0.872340 (-4000 675);
PAINT GREEN (-4000 675);
DISPLAY INVISIBLE (-4000 675);
FORCEPROP 1 LAST SIZE 1B
J 0
(-3925 475);
DISPLAY 0.872340 (-3925 475);
PAINT GREEN (-3925 475);
DISPLAY INVISIBLE (-3925 475);
FORCEPROP 1 LAST VOLTAGE 0
J 0
(-4000 525);
PAINT SKYBLUE (-4000 525);
DISPLAY INVISIBLE (-4000 525);
FORCEPROP 1 LAST BODY_TYPE PLUMBING
J 0
(-4045 482);
DISPLAY 0.340426 (-4045 482);
PAINT GREEN (-4045 482);
DISPLAY INVISIBLE (-4045 482);
FORCEPROP 2 LAST ROOM PVPP_KLM_VR
J 0
(-4575 600);
DISPLAY 1.042553 (-4575 600);
PAINT GREEN (-4575 600);
DISPLAY INVISIBLE (-4575 600);
FORCEPROP 2 LAST BOM_COST PVPP_KLM_VR
J 0
(-4850 600);
DISPLAY 1.042553 (-4850 600);
PAINT WHITE (-4850 600);
DISPLAY INVISIBLE (-4850 600);
FORCEPROP 2 LAST CDS_LIB mstr_symbols
J 0
(-4000 525);
PAINT MONO (-4000 525);
DISPLAY INVISIBLE (-4000 525);
FORCEPROP 1 LAST PATH I247
J 0
(-3925 525);
DISPLAY 0.872340 (-3925 525);
PAINT AQUA (-3925 525);
DISPLAY INVISIBLE (-3925 525);
FORCEADD SC22U16V5MX-4-GP..1
(-4000 800);
FORCEPROP 2 LAST PACK_SIZE 0805
J 0
(-3900 700);
DISPLAY 0.638298 (-3900 700);
PAINT GREEN (-3900 700);
FORCEPROP 2 LAST TOLERANCE 20%
J 0
(-3900 850);
DISPLAY 0.638298 (-3900 850);
PAINT GREEN (-3900 850);
FORCEPROP 1 LAST VALUE SC22U16V5MX-4-GP
R 1
J 0
(-3925 595);
DISPLAY 0.617021 (-3925 595);
PAINT GREEN (-3925 595);
FORCEPROP 2 LAST ATTRIBUTE 22UF
J 0
(-3900 900);
DISPLAY 0.638298 (-3900 900);
PAINT GREEN (-3900 900);
FORCEPROP 1 LAST LOCATION C9E6
J 0
(-3900 960);
DISPLAY 0.617021 (-3900 960);
PAINT GREEN (-3900 960);
FORCEPROP 2 LASTPIN (-4000 875) $PN 1
R 1
J 0
(-4010 885);
DISPLAY 0.808511 (-4010 885);
PAINT ORANGE (-4010 885);
FORCEPROP 2 LAST TYPE X6S
J 0
(-3900 750);
DISPLAY 0.638298 (-3900 750);
PAINT GREEN (-3900 750);
FORCEPROP 2 LASTPIN (-4000 725) $PN 2
R 1
J 2
(-4010 715);
DISPLAY 0.808511 (-4010 715);
PAINT ORANGE (-4010 715);
FORCEPROP 0 LAST POP NOPOP
J 0
(-3900 650);
DISPLAY 0.638298 (-3900 650);
PAINT RED (-3900 650);
FORCEPROP 2 LAST RATED 16V
J 0
(-3900 800);
DISPLAY 0.638298 (-3900 800);
PAINT GREEN (-3900 800);
FORCEPROP 0 LAST GROUP NI_I210&RJ45
J 0
(-3944 563);
DISPLAY 0.638298 (-3944 563);
PAINT BROWN (-3944 563);
DISPLAY BOTH (-3944 563);
FORCEPROP 1 LAST PATH I248
J 0
(-4000 800);
DISPLAY 0.617021 (-4000 800);
PAINT GREEN (-4000 800);
DISPLAY INVISIBLE (-4000 800);
FORCEPROP 1 LAST CDS_LMAN_SYM_OUTLINE -50,25,50,-25
J 0
(-4000 800);
DISPLAY 0.468085 (-4000 800);
PAINT GREEN (-4000 800);
DISPLAY INVISIBLE (-4000 800);
FORCEPROP 2 LAST CDS_LIB w_hdl
J 0
(-4000 800);
PAINT MONO (-4000 800);
DISPLAY INVISIBLE (-4000 800);
FORCEPROP 1 LAST PART_NUMBER 078.22611.0811
J 0
(-4000 800);
DISPLAY 0.617021 (-4000 800);
PAINT GREEN (-4000 800);
DISPLAY INVISIBLE (-4000 800);
FORCEPROP 2 LAST SEC_TYPE SMD-BCG5
J 0
(-3975 875);
DISPLAY 1.021277 (-3975 875);
PAINT ORANGE (-3975 875);
DISPLAY INVISIBLE (-3975 875);
FORCEPROP 2 LAST SEC 1
J 0
(-3975 875);
DISPLAY 0.680851 (-3975 875);
PAINT MONO (-3975 875);
DISPLAY INVISIBLE (-3975 875);
FORCEPROP 1 LAST PACK_TYPE SMD-BCG5
J 0
(-4000 800);
DISPLAY 0.617021 (-4000 800);
PAINT GREEN (-4000 800);
DISPLAY INVISIBLE (-4000 800);
FORCEADD CAP..1
(-7750 1200);
FORCEPROP 1 LAST LOCATION C9E9
J 0
(-7700 1300);
DISPLAY 0.617021 (-7700 1300);
PAINT AQUA (-7700 1300);
FORCEPROP 1 LAST VALUE 15.0PF
J 0
(-7700 1250);
DISPLAY 0.617021 (-7700 1250);
PAINT SKYBLUE (-7700 1250);
FORCEPROP 1 LAST PART_NUMBER A36095-047
J 0
(-7700 1050);
DISPLAY 0.617021 (-7700 1050);
PAINT BLUE (-7700 1050);
FORCEPROP 1 LASTPIN (-7750 1300) $PN 1
J 0
(-7740 1280);
DISPLAY 0.617021 (-7740 1280);
PAINT ORANGE (-7740 1280);
FORCEPROP 1 LAST TOLERANCE 5%
J 0
(-7700 1150);
DISPLAY 0.617021 (-7700 1150);
PAINT SKYBLUE (-7700 1150);
FORCEPROP 1 LASTPIN (-7750 1100) $PN 2
J 0
(-7740 1080);
DISPLAY 0.617021 (-7740 1080);
PAINT ORANGE (-7740 1080);
FORCEPROP 1 LAST VOLTAGE 50V
J 0
(-7700 1200);
DISPLAY 0.617021 (-7700 1200);
PAINT SKYBLUE (-7700 1200);
FORCEPROP 1 LAST PACK_TYPE 0402LF
J 0
(-7700 1000);
DISPLAY 0.617021 (-7700 1000);
PAINT SKYBLUE (-7700 1000);
FORCEPROP 1 LAST MATERIAL COG
J 0
(-7700 1100);
DISPLAY 0.617021 (-7700 1100);
PAINT SKYBLUE (-7700 1100);
FORCEPROP 0 LAST GROUP NI_I210&RJ45
J 0
(-7719 963);
DISPLAY 0.638298 (-7719 963);
PAINT BROWN (-7719 963);
DISPLAY BOTH (-7719 963);
FORCEPROP 2 LAST BOM_COST SYS_CLOCK
J 0
(-7610 1010);
PAINT MONO (-7610 1010);
DISPLAY INVISIBLE (-7610 1010);
FORCEPROP 2 LAST ROOM SB
J 0
(-7750 1200);
PAINT MONO (-7750 1200);
DISPLAY INVISIBLE (-7750 1200);
FORCEPROP 2 LAST CDS_LIB mstr_discrete
J 0
(-7750 1200);
PAINT ORANGE (-7750 1200);
DISPLAY INVISIBLE (-7750 1200);
FORCEPROP 2 LAST SEC 1
J 0
(-7700 1400);
DISPLAY 0.680851 (-7700 1400);
PAINT MONO (-7700 1400);
DISPLAY INVISIBLE (-7700 1400);
FORCEPROP 2 LAST SEC_TYPE 0402LF
J 0
(-7700 1400);
DISPLAY 1.021277 (-7700 1400);
PAINT ORANGE (-7700 1400);
DISPLAY INVISIBLE (-7700 1400);
FORCEPROP 1 LAST PATH I249
J 0
(-7700 1350);
DISPLAY 0.978723 (-7700 1350);
PAINT WHITE (-7700 1350);
DISPLAY INVISIBLE (-7700 1350);
FORCEPROP 2 LAST CDS_LOCATION C9E9
J 0
(-7700 1300);
DISPLAY 0.617021 (-7700 1300);
PAINT AQUA (-7700 1300);
DISPLAY INVISIBLE (-7700 1300);
FORCEADD CAP..1
(-7325 1200);
FORCEPROP 1 LAST PACK_TYPE 0402LF
J 0
(-7275 1000);
DISPLAY 0.617021 (-7275 1000);
PAINT SKYBLUE (-7275 1000);
FORCEPROP 1 LAST PART_NUMBER A36095-047
J 0
(-7275 1050);
DISPLAY 0.617021 (-7275 1050);
PAINT BLUE (-7275 1050);
FORCEPROP 1 LAST VALUE 15.0PF
J 0
(-7275 1250);
DISPLAY 0.617021 (-7275 1250);
PAINT SKYBLUE (-7275 1250);
FORCEPROP 1 LAST VOLTAGE 50V
J 0
(-7275 1200);
DISPLAY 0.617021 (-7275 1200);
PAINT SKYBLUE (-7275 1200);
FORCEPROP 1 LAST LOCATION C9E8
J 0
(-7275 1300);
DISPLAY 0.617021 (-7275 1300);
PAINT AQUA (-7275 1300);
FORCEPROP 1 LASTPIN (-7325 1100) $PN 2
J 0
(-7315 1080);
DISPLAY 0.617021 (-7315 1080);
PAINT ORANGE (-7315 1080);
FORCEPROP 1 LAST MATERIAL COG
J 0
(-7275 1100);
DISPLAY 0.617021 (-7275 1100);
PAINT SKYBLUE (-7275 1100);
FORCEPROP 1 LAST TOLERANCE 5%
J 0
(-7275 1150);
DISPLAY 0.617021 (-7275 1150);
PAINT SKYBLUE (-7275 1150);
FORCEPROP 1 LASTPIN (-7325 1300) $PN 1
J 0
(-7315 1280);
DISPLAY 0.617021 (-7315 1280);
PAINT ORANGE (-7315 1280);
FORCEPROP 0 LAST GROUP NI_I210&RJ45
J 0
(-7269 963);
DISPLAY 0.638298 (-7269 963);
PAINT BROWN (-7269 963);
DISPLAY BOTH (-7269 963);
FORCEPROP 1 LAST PATH I250
J 0
(-7275 1350);
DISPLAY 0.978723 (-7275 1350);
PAINT WHITE (-7275 1350);
DISPLAY INVISIBLE (-7275 1350);
FORCEPROP 2 LAST SEC_TYPE 0402LF
J 0
(-7275 1400);
DISPLAY 1.021277 (-7275 1400);
PAINT ORANGE (-7275 1400);
DISPLAY INVISIBLE (-7275 1400);
FORCEPROP 2 LAST SEC 1
J 0
(-7275 1400);
DISPLAY 0.680851 (-7275 1400);
PAINT MONO (-7275 1400);
DISPLAY INVISIBLE (-7275 1400);
FORCEPROP 2 LAST CDS_LIB mstr_discrete
J 0
(-7325 1200);
PAINT ORANGE (-7325 1200);
DISPLAY INVISIBLE (-7325 1200);
FORCEPROP 2 LAST ROOM SB
J 0
(-7325 1200);
PAINT MONO (-7325 1200);
DISPLAY INVISIBLE (-7325 1200);
FORCEPROP 2 LAST BOM_COST SYS_CLOCK
J 0
(-7185 1010);
PAINT MONO (-7185 1010);
DISPLAY INVISIBLE (-7185 1010);
FORCEPROP 2 LAST CDS_LOCATION C9E8
J 0
(-7275 1300);
DISPLAY 0.617021 (-7275 1300);
PAINT AQUA (-7275 1300);
DISPLAY INVISIBLE (-7275 1300);
FORCEADD OFFPAGE..4
(-2350 3175);
FORCEPROP 2 LAST $XR0 118 
J 0
(-2164 3175);
DISPLAY 0.638298 (-2164 3175);
PAINT MONO (-2164 3175);
FORCEPROP 2 LAST PATH I251
J 0
(-2150 3225);
DISPLAY 1.021277 (-2150 3225);
PAINT ORANGE (-2150 3225);
DISPLAY INVISIBLE (-2150 3225);
FORCEPROP 2 LAST CDS_LIB mstr_standard
J 0
(-2350 3175);
PAINT ORANGE (-2350 3175);
DISPLAY INVISIBLE (-2350 3175);
FORCEPROP 1 LAST OFFPAGE TRUE
J 0
(-2025 3050);
DISPLAY 0.872340 (-2025 3050);
PAINT GREEN (-2025 3050);
DISPLAY INVISIBLE (-2025 3050);
FORCEPROP 1 LAST COMMENT_BODY TRUE
J 0
(-2375 3075);
DISPLAY 0.872340 (-2375 3075);
PAINT GREEN (-2375 3075);
DISPLAY INVISIBLE (-2375 3075);
FORCEADD RES..2
(-6950 3275);
FORCEPROP 1 LAST LOCATION R9W36
J 0
(-6905 3400);
DISPLAY 0.617021 (-6905 3400);
PAINT AQUA (-6905 3400);
FORCEPROP 1 LAST VALUE 10.0K
J 0
(-6905 3350);
DISPLAY 0.617021 (-6905 3350);
PAINT SKYBLUE (-6905 3350);
FORCEPROP 1 LAST TOLERANCE 1%
J 0
(-6905 3300);
DISPLAY 0.617021 (-6905 3300);
PAINT SKYBLUE (-6905 3300);
FORCEPROP 1 LASTPIN (-6950 3375) $PN 1
J 0
(-6945 3337);
DISPLAY 0.617021 (-6945 3337);
PAINT ORANGE (-6945 3337);
FORCEPROP 1 LAST PACK_TYPE 0402
J 0
(-6910 3100);
DISPLAY 0.617021 (-6910 3100);
PAINT SKYBLUE (-6910 3100);
FORCEPROP 1 LASTPIN (-6950 3175) $PN 2
J 0
(-6945 3185);
DISPLAY 0.617021 (-6945 3185);
PAINT ORANGE (-6945 3185);
FORCEPROP 1 LAST MATERIAL CHIP
J 0
(-6910 3200);
DISPLAY 0.617021 (-6910 3200);
PAINT SKYBLUE (-6910 3200);
FORCEPROP 1 LAST WATTAGE 1/16W
J 0
(-6910 3250);
DISPLAY 0.617021 (-6910 3250);
PAINT SKYBLUE (-6910 3250);
FORCEPROP 0 LAST GROUP NI_I210&RJ45
J 0
(-6769 3088);
DISPLAY 0.638298 (-6769 3088);
PAINT BROWN (-6769 3088);
DISPLAY BOTH (-6769 3088);
FORCEPROP 1 LAST PART_NUMBER G21796-016
J 0
(-6910 3150);
DISPLAY 0.617021 (-6910 3150);
PAINT BLUE (-6910 3150);
FORCEPROP 1 LAST PATH I252
J 0
(-6900 3450);
DISPLAY 0.978723 (-6900 3450);
PAINT WHITE (-6900 3450);
DISPLAY INVISIBLE (-6900 3450);
FORCEPROP 2 LAST BOM_COST NT_GBE_BASE
J 0
(-6900 3500);
DISPLAY 1.021277 (-6900 3500);
PAINT ORANGE (-6900 3500);
DISPLAY INVISIBLE (-6900 3500);
FORCEPROP 2 LAST SEC_TYPE 0402
J 0
(-6900 3500);
DISPLAY 1.021277 (-6900 3500);
PAINT ORANGE (-6900 3500);
DISPLAY INVISIBLE (-6900 3500);
FORCEPROP 2 LAST SEC 1
J 0
(-6900 3500);
DISPLAY 0.680851 (-6900 3500);
PAINT MONO (-6900 3500);
DISPLAY INVISIBLE (-6900 3500);
FORCEPROP 2 LAST ROOM NIC_SPRV
J 0
(-6900 3450);
DISPLAY 1.021277 (-6900 3450);
PAINT ORANGE (-6900 3450);
DISPLAY INVISIBLE (-6900 3450);
FORCEPROP 2 LAST CDS_LIB mstr_discrete
J 0
(-6950 3275);
PAINT ORANGE (-6950 3275);
DISPLAY INVISIBLE (-6950 3275);
FORCEPROP 2 LAST CDS_LOCATION R9W36
J 0
(-6905 3400);
DISPLAY 0.617021 (-6905 3400);
PAINT AQUA (-6905 3400);
DISPLAY INVISIBLE (-6905 3400);
FORCEADD SPRINGVILLE..2
(-4200 3125);
FORCEPROP 2 LASTPIN (-5100 4275) $PN 42
J 2
(-5110 4285);
DISPLAY 0.617021 (-5110 4285);
PAINT ORANGE (-5110 4285);
FORCEPROP 2 LASTPIN (-5100 4225) $PN 11
J 2
(-5110 4235);
DISPLAY 0.617021 (-5110 4235);
PAINT ORANGE (-5110 4235);
FORCEPROP 2 LASTPIN (-5100 3225) $PN 45
J 2
(-5110 3235);
DISPLAY 0.617021 (-5110 3235);
PAINT ORANGE (-5110 3235);
FORCEPROP 2 LASTPIN (-5100 2925) $PN 19
J 2
(-5110 2935);
DISPLAY 0.617021 (-5110 2935);
PAINT ORANGE (-5110 2935);
FORCEPROP 2 LASTPIN (-5100 3025) $PN 48
J 2
(-5110 3035);
DISPLAY 0.617021 (-5110 3035);
PAINT ORANGE (-5110 3035);
FORCEPROP 1 LAST PART_NUMBER G47144-004
J 0
(-5050 1675);
DISPLAY 0.617021 (-5050 1675);
PAINT BLUE (-5050 1675);
FORCEPROP 2 LASTPIN (-5100 3625) $PN 27
J 2
(-5110 3635);
DISPLAY 0.617021 (-5110 3635);
PAINT ORANGE (-5110 3635);
FORCEPROP 2 LASTPIN (-5100 3475) $PN 64
J 2
(-5110 3485);
DISPLAY 0.617021 (-5110 3485);
PAINT ORANGE (-5110 3485);
FORCEPROP 2 LASTPIN (-5100 2375) $PN 14
J 2
(-5110 2385);
DISPLAY 0.617021 (-5110 2385);
PAINT ORANGE (-5110 2385);
FORCEPROP 2 LASTPIN (-3300 1875) $PN 65
J 0
(-3290 1885);
DISPLAY 0.617021 (-3290 1885);
PAINT ORANGE (-3290 1885);
FORCEPROP 2 LASTPIN (-5100 2675) $PN 7
J 2
(-5110 2685);
DISPLAY 0.617021 (-5110 2685);
PAINT ORANGE (-5110 2685);
FORCEPROP 2 LASTPIN (-3300 2375) $PN 12
J 0
(-3290 2385);
DISPLAY 0.617021 (-3290 2385);
PAINT ORANGE (-3290 2385);
FORCEPROP 2 LASTPIN (-5100 1925) $PN 25
J 2
(-5110 1935);
DISPLAY 0.617021 (-5110 1935);
PAINT ORANGE (-5110 1935);
FORCEPROP 2 LASTPIN (-3300 1975) $PN 22
J 0
(-3290 1985);
DISPLAY 0.617021 (-3290 1985);
PAINT ORANGE (-3290 1985);
FORCEPROP 1 LAST LOCATION EU9E1
J 0
(-5050 4525);
DISPLAY 0.617021 (-5050 4525);
PAINT AQUA (-5050 4525);
FORCEPROP 1 LAST MATERIAL IC
J 0
(-5050 4475);
DISPLAY 0.617021 (-5050 4475);
PAINT SKYBLUE (-5050 4475);
FORCEPROP 2 LASTPIN (-5100 1975) $PN 26
J 2
(-5110 1985);
DISPLAY 0.617021 (-5110 1985);
PAINT ORANGE (-5110 1985);
FORCEPROP 2 LASTPIN (-5100 3125) $PN 28
J 2
(-5110 3135);
DISPLAY 0.617021 (-5110 3135);
PAINT ORANGE (-5110 3135);
FORCEPROP 2 LASTPIN (-5100 2825) $PN 29
J 2
(-5110 2835);
DISPLAY 0.617021 (-5110 2835);
PAINT ORANGE (-5110 2835);
FORCEPROP 2 LASTPIN (-5100 2875) $PN 18
J 2
(-5110 2885);
DISPLAY 0.617021 (-5110 2885);
PAINT ORANGE (-5110 2885);
FORCEPROP 2 LASTPIN (-5100 3075) $PN 1
J 2
(-5110 3085);
DISPLAY 0.617021 (-5110 3085);
PAINT ORANGE (-5110 3085);
FORCEPROP 2 LASTPIN (-5100 2725) $PN 2
J 2
(-5110 2735);
DISPLAY 0.617021 (-5110 2735);
PAINT ORANGE (-5110 2735);
FORCEPROP 2 LASTPIN (-5100 2525) $PN 8
J 2
(-5110 2535);
DISPLAY 0.617021 (-5110 2535);
PAINT ORANGE (-5110 2535);
FORCEPROP 2 LASTPIN (-5100 2075) $PN 23
J 2
(-5110 2085);
DISPLAY 0.617021 (-5110 2085);
PAINT ORANGE (-5110 2085);
FORCEPROP 2 LASTPIN (-5100 2125) $PN 24
J 2
(-5110 2135);
DISPLAY 0.617021 (-5110 2135);
PAINT ORANGE (-5110 2135);
FORCEPROP 2 LASTPIN (-5100 2275) $PN 17
J 2
(-5110 2285);
DISPLAY 0.617021 (-5110 2285);
PAINT ORANGE (-5110 2285);
FORCEPROP 2 LASTPIN (-5100 4025) $PN 38
J 2
(-5110 4035);
DISPLAY 0.617021 (-5110 4035);
PAINT ORANGE (-5110 4035);
FORCEPROP 2 LASTPIN (-5100 3875) $PN 56
J 2
(-5110 3885);
DISPLAY 0.617021 (-5110 3885);
PAINT ORANGE (-5110 3885);
FORCEPROP 2 LASTPIN (-5100 3925) $PN 47
J 2
(-5110 3935);
DISPLAY 0.617021 (-5110 3935);
PAINT ORANGE (-5110 3935);
FORCEPROP 2 LASTPIN (-5100 3775) $PN 39
J 2
(-5110 3785);
DISPLAY 0.617021 (-5110 3785);
PAINT ORANGE (-5110 3785);
FORCEPROP 2 LASTPIN (-5100 3525) $PN 51
J 2
(-5110 3535);
DISPLAY 0.617021 (-5110 3535);
PAINT ORANGE (-5110 3535);
FORCEPROP 2 LASTPIN (-5100 3575) $PN 41
J 2
(-5110 3585);
DISPLAY 0.617021 (-5110 3585);
PAINT ORANGE (-5110 3585);
FORCEPROP 2 LASTPIN (-5100 4175) $PN 32
J 2
(-5110 4185);
DISPLAY 0.617021 (-5110 4185);
PAINT ORANGE (-5110 4185);
FORCEPROP 2 LASTPIN (-3300 2125) $PN 21
J 0
(-3290 2135);
DISPLAY 0.617021 (-3290 2135);
PAINT ORANGE (-3290 2135);
FORCEPROP 2 LASTPIN (-3300 2075) $PN 20
J 0
(-3290 2085);
DISPLAY 0.617021 (-3290 2085);
PAINT ORANGE (-3290 2085);
FORCEPROP 2 LASTPIN (-3300 2275) $PN 13
J 0
(-3290 2285);
DISPLAY 0.617021 (-3290 2285);
PAINT ORANGE (-3290 2285);
FORCEPROP 2 LASTPIN (-3300 2325) $PN 15
J 0
(-3290 2335);
DISPLAY 0.617021 (-3290 2335);
PAINT ORANGE (-3290 2335);
FORCEPROP 2 LASTPIN (-3300 2475) $PN 6
J 0
(-3290 2485);
DISPLAY 0.617021 (-3290 2485);
PAINT ORANGE (-3290 2485);
FORCEPROP 2 LASTPIN (-3300 2525) $PN 5
J 0
(-3290 2535);
DISPLAY 0.617021 (-3290 2535);
PAINT ORANGE (-3290 2535);
FORCEPROP 2 LASTPIN (-3300 2675) $PN 3
J 0
(-3290 2685);
DISPLAY 0.617021 (-3290 2685);
PAINT ORANGE (-3290 2685);
FORCEPROP 2 LASTPIN (-3300 2725) $PN 44
J 0
(-3290 2735);
DISPLAY 0.617021 (-3290 2735);
PAINT ORANGE (-3290 2735);
FORCEPROP 2 LASTPIN (-3300 2975) $PN 36
J 0
(-3290 2985);
DISPLAY 0.617021 (-3290 2985);
PAINT ORANGE (-3290 2985);
FORCEPROP 2 LASTPIN (-3300 3025) $PN 34
J 0
(-3290 3035);
DISPLAY 0.617021 (-3290 3035);
PAINT ORANGE (-3290 3035);
FORCEPROP 2 LASTPIN (-3300 2925) $PN 35
J 0
(-3290 2935);
DISPLAY 0.617021 (-3290 2935);
PAINT ORANGE (-3290 2935);
FORCEPROP 2 LASTPIN (-3300 2825) $PN 4
J 0
(-3290 2835);
DISPLAY 0.617021 (-3290 2835);
PAINT ORANGE (-3290 2835);
FORCEPROP 2 LASTPIN (-3300 3275) $PN 60
J 0
(-3290 3285);
DISPLAY 0.617021 (-3290 3285);
PAINT ORANGE (-3290 3285);
FORCEPROP 2 LASTPIN (-3300 3225) $PN 62
J 0
(-3290 3235);
DISPLAY 0.617021 (-3290 3235);
PAINT ORANGE (-3290 3235);
FORCEPROP 2 LASTPIN (-3300 3175) $PN 61
J 0
(-3290 3185);
DISPLAY 0.617021 (-3290 3185);
PAINT ORANGE (-3290 3185);
FORCEPROP 2 LASTPIN (-3300 3125) $PN 63
J 0
(-3290 3135);
DISPLAY 0.617021 (-3290 3135);
PAINT ORANGE (-3290 3135);
FORCEPROP 2 LASTPIN (-3300 3375) $PN 37
J 0
(-3290 3385);
DISPLAY 0.617021 (-3290 3385);
PAINT ORANGE (-3290 3385);
FORCEPROP 2 LASTPIN (-3300 3775) $PN 30
J 0
(-3290 3785);
DISPLAY 0.617021 (-3290 3785);
PAINT ORANGE (-3290 3785);
FORCEPROP 2 LASTPIN (-3300 3625) $PN 40
J 0
(-3290 3635);
DISPLAY 0.617021 (-3290 3635);
PAINT ORANGE (-3290 3635);
FORCEPROP 2 LASTPIN (-3300 3975) $PN 58
J 0
(-3290 3985);
DISPLAY 0.617021 (-3290 3985);
PAINT ORANGE (-3290 3985);
FORCEPROP 2 LASTPIN (-3300 4025) $PN 54
J 0
(-3290 4035);
DISPLAY 0.617021 (-3290 4035);
PAINT ORANGE (-3290 4035);
FORCEPROP 2 LASTPIN (-3300 3925) $PN 57
J 0
(-3290 3935);
DISPLAY 0.617021 (-3290 3935);
PAINT ORANGE (-3290 3935);
FORCEPROP 2 LASTPIN (-3300 4075) $PN 55
J 0
(-3290 4085);
DISPLAY 0.617021 (-3290 4085);
PAINT ORANGE (-3290 4085);
FORCEPROP 2 LASTPIN (-3300 4125) $PN 52
J 0
(-3290 4135);
DISPLAY 0.617021 (-3290 4135);
PAINT ORANGE (-3290 4135);
FORCEPROP 2 LASTPIN (-3300 4225) $PN 49
J 0
(-3290 4235);
DISPLAY 0.617021 (-3290 4235);
PAINT ORANGE (-3290 4235);
FORCEPROP 2 LASTPIN (-3300 4175) $PN 53
J 0
(-3290 4185);
DISPLAY 0.617021 (-3290 4185);
PAINT ORANGE (-3290 4185);
FORCEPROP 2 LASTPIN (-3300 4275) $PN 50
J 0
(-3290 4285);
DISPLAY 0.617021 (-3290 4285);
PAINT ORANGE (-3290 4285);
FORCEPROP 2 LASTPIN (-5100 2475) $PN 9
J 2
(-5110 2485);
DISPLAY 0.617021 (-5110 2485);
PAINT ORANGE (-5110 2485);
FORCEPROP 2 LASTPIN (-3300 3825) $PN 33
J 0
(-3290 3835);
DISPLAY 0.617021 (-3290 3835);
PAINT ORANGE (-3290 3835);
FORCEPROP 2 LASTPIN (-5100 2625) $PN 43
J 2
(-5110 2635);
DISPLAY 0.617021 (-5110 2635);
PAINT ORANGE (-5110 2635);
FORCEPROP 2 LASTPIN (-5100 2225) $PN 16
J 2
(-5110 2235);
DISPLAY 0.617021 (-5110 2235);
PAINT ORANGE (-5110 2235);
FORCEPROP 2 LASTPIN (-5100 3375) $PN 46
J 2
(-5110 3385);
DISPLAY 0.617021 (-5110 3385);
PAINT ORANGE (-5110 3385);
FORCEPROP 0 LAST GROUP NI_I210&RJ45
J 0
(-4669 1688);
DISPLAY 0.638298 (-4669 1688);
PAINT BROWN (-4669 1688);
DISPLAY BOTH (-4669 1688);
FORCEPROP 2 LASTPIN (-5100 3675) $PN 10
J 2
(-5110 3685);
DISPLAY 0.617021 (-5110 3685);
PAINT ORANGE (-5110 3685);
FORCEPROP 2 LASTPIN (-5100 4125) $PN 59
J 2
(-5110 4135);
DISPLAY 0.617021 (-5110 4135);
PAINT ORANGE (-5110 4135);
FORCEPROP 2 LASTPIN (-3300 3725) $PN 31
J 0
(-3290 3735);
DISPLAY 0.617021 (-3290 3735);
PAINT ORANGE (-3290 3735);
FORCEPROP 2 LAST CDS_LIB mstr_intel
J 0
(-4200 3125);
PAINT ORANGE (-4200 3125);
DISPLAY INVISIBLE (-4200 3125);
FORCEPROP 2 LAST SEC 1
J 0
(-5050 4575);
DISPLAY 0.680851 (-5050 4575);
PAINT MONO (-5050 4575);
DISPLAY INVISIBLE (-5050 4575);
FORCEPROP 2 LAST CDS_LOCATION EU9E1
J 0
(-5050 4525);
DISPLAY 0.617021 (-5050 4525);
PAINT AQUA (-5050 4525);
DISPLAY INVISIBLE (-5050 4525);
FORCEPROP 1 LAST PACK_TYPE SM1
J 0
(-5050 4575);
PAINT SKYBLUE (-5050 4575);
DISPLAY INVISIBLE (-5050 4575);
FORCEPROP 2 LAST SEC_TYPE SM1
J 0
(-5050 4575);
DISPLAY 1.021277 (-5050 4575);
PAINT ORANGE (-5050 4575);
DISPLAY INVISIBLE (-5050 4575);
FORCEPROP 2 LAST ROOM NIC_SPRV
J 0
(-5050 4575);
DISPLAY 1.021277 (-5050 4575);
PAINT ORANGE (-5050 4575);
DISPLAY INVISIBLE (-5050 4575);
FORCEPROP 2 LAST BOM_COST NT_GBE_BASE
J 0
(-5050 4625);
DISPLAY 1.021277 (-5050 4625);
PAINT ORANGE (-5050 4625);
DISPLAY INVISIBLE (-5050 4625);
FORCEPROP 1 LAST PATH I72
J 0
(-4200 4475);
PAINT GREEN (-4200 4475);
DISPLAY INVISIBLE (-4200 4475);
FORCEADD P0V9_LAN..1
(-5725 4525);
FORCEPROP 3 LASTPIN (-5725 4475) SIG_NAME P0V9_LAN\g
J 0
(-5715 4485);
DISPLAY 0.659574 (-5715 4485);
PAINT MONO (-5715 4485);
DISPLAY INVISIBLE (-5715 4485);
FORCEPROP 1 LAST VOLTAGE 0.9V
J 0
(-5770 4482);
DISPLAY 0.340426 (-5770 4482);
PAINT SKYBLUE (-5770 4482);
DISPLAY INVISIBLE (-5770 4482);
FORCEPROP 2 LAST CDS_LIB mstr_symbols
J 0
(-5725 4525);
PAINT ORANGE (-5725 4525);
DISPLAY INVISIBLE (-5725 4525);
FORCEPROP 1 LAST PATH I73
J 0
(-5675 4550);
DISPLAY 0.872340 (-5675 4550);
PAINT AQUA (-5675 4550);
DISPLAY INVISIBLE (-5675 4550);
FORCEPROP 1 LAST BODY_TYPE PLUMBING
J 0
(-5770 4482);
DISPLAY 0.340426 (-5770 4482);
PAINT GREEN (-5770 4482);
DISPLAY INVISIBLE (-5770 4482);
FORCEPROP 1 LAST HDL_POWER P0V9_LAN
J 1
(-5725 4575);
DISPLAY 0.872340 (-5725 4575);
PAINT GREEN (-5725 4575);
DISPLAY INVISIBLE (-5725 4575);
FORCEADD P1V5_LAN..1
(-6375 4300);
FORCEPROP 3 LASTPIN (-6375 4250) SIG_NAME P1V5_LAN\g
J 0
(-6365 4260);
DISPLAY 0.659574 (-6365 4260);
PAINT MONO (-6365 4260);
DISPLAY INVISIBLE (-6365 4260);
FORCEPROP 1 LAST HDL_POWER P1V5_LAN
J 1
(-6375 4350);
DISPLAY 0.872340 (-6375 4350);
PAINT GREEN (-6375 4350);
DISPLAY INVISIBLE (-6375 4350);
FORCEPROP 1 LAST BODY_TYPE PLUMBING
J 0
(-6420 4257);
DISPLAY 0.340426 (-6420 4257);
PAINT GREEN (-6420 4257);
DISPLAY INVISIBLE (-6420 4257);
FORCEPROP 1 LAST PATH I74
J 0
(-6325 4325);
DISPLAY 0.872340 (-6325 4325);
PAINT AQUA (-6325 4325);
DISPLAY INVISIBLE (-6325 4325);
FORCEPROP 2 LAST CDS_LIB mstr_symbols
J 0
(-6375 4300);
PAINT ORANGE (-6375 4300);
DISPLAY INVISIBLE (-6375 4300);
FORCEPROP 1 LAST VOLTAGE 1.5V
J 0
(-6420 4257);
DISPLAY 0.340426 (-6420 4257);
PAINT SKYBLUE (-6420 4257);
DISPLAY INVISIBLE (-6420 4257);
FORCEADD CAP..1
(-2725 3500);
FORCEPROP 0 LAST GROUP NI_I210&RJ45
J 0
(-2669 3338);
DISPLAY 0.638298 (-2669 3338);
PAINT BROWN (-2669 3338);
DISPLAY BOTH (-2669 3338);
FORCEPROP 1 LAST PART_NUMBER A36096-063
J 0
(-2975 3450);
DISPLAY 0.617021 (-2975 3450);
PAINT BLUE (-2975 3450);
FORCEPROP 1 LAST VALUE 0.039UF
J 0
(-2675 3550);
DISPLAY 0.617021 (-2675 3550);
PAINT SKYBLUE (-2675 3550);
FORCEPROP 1 LASTPIN (-2725 3600) $PN 1
J 0
(-2715 3580);
DISPLAY 0.617021 (-2715 3580);
PAINT ORANGE (-2715 3580);
FORCEPROP 1 LAST PACK_TYPE 0402LF
J 0
(-2925 3400);
DISPLAY 0.617021 (-2925 3400);
PAINT SKYBLUE (-2925 3400);
FORCEPROP 1 LAST TOLERANCE 10%
J 0
(-2675 3450);
DISPLAY 0.617021 (-2675 3450);
PAINT SKYBLUE (-2675 3450);
FORCEPROP 1 LASTPIN (-2725 3400) $PN 2
J 0
(-2715 3380);
DISPLAY 0.617021 (-2715 3380);
PAINT ORANGE (-2715 3380);
FORCEPROP 1 LAST LOCATION C9E7
J 0
(-2675 3600);
DISPLAY 0.617021 (-2675 3600);
PAINT AQUA (-2675 3600);
FORCEPROP 1 LAST MATERIAL X7R
J 0
(-2675 3400);
DISPLAY 0.617021 (-2675 3400);
PAINT SKYBLUE (-2675 3400);
FORCEPROP 1 LAST VOLTAGE 25V
J 0
(-2675 3500);
DISPLAY 0.617021 (-2675 3500);
PAINT SKYBLUE (-2675 3500);
FORCEPROP 2 LAST CDS_LIB mstr_discrete
J 0
(-2725 3500);
PAINT ORANGE (-2725 3500);
DISPLAY INVISIBLE (-2725 3500);
FORCEPROP 2 LAST ROOM NIC_SPRV
J 0
(-2675 3650);
DISPLAY 1.021277 (-2675 3650);
PAINT ORANGE (-2675 3650);
DISPLAY INVISIBLE (-2675 3650);
FORCEPROP 1 LAST PATH I76
J 0
(-2675 3650);
DISPLAY 0.978723 (-2675 3650);
PAINT WHITE (-2675 3650);
DISPLAY INVISIBLE (-2675 3650);
FORCEPROP 2 LAST CDS_LOCATION C9E7
J 0
(-2675 3600);
DISPLAY 0.617021 (-2675 3600);
PAINT AQUA (-2675 3600);
DISPLAY INVISIBLE (-2675 3600);
FORCEPROP 2 LAST SEC 1
J 0
(-2675 3700);
PAINT MONO (-2675 3700);
DISPLAY INVISIBLE (-2675 3700);
FORCEPROP 2 LAST BOM_COST NT_GBE_BASE
J 0
(-2675 3700);
DISPLAY 1.021277 (-2675 3700);
PAINT ORANGE (-2675 3700);
DISPLAY INVISIBLE (-2675 3700);
FORCEPROP 2 LAST SEC_TYPE 0402LF
J 0
(-2675 3700);
DISPLAY 1.021277 (-2675 3700);
PAINT ORANGE (-2675 3700);
DISPLAY INVISIBLE (-2675 3700);
FORCEADD GND..1
(-3175 1425);
FORCEPROP 3 LASTPIN (-3175 1475) SIG_NAME GND\g
J 0
(-3165 1485);
DISPLAY 0.659574 (-3165 1485);
PAINT MONO (-3165 1485);
DISPLAY INVISIBLE (-3165 1485);
FORCEPROP 1 LAST VOLTAGE 0.0V
J 0
(-3220 1382);
DISPLAY 0.340426 (-3220 1382);
PAINT SKYBLUE (-3220 1382);
DISPLAY INVISIBLE (-3220 1382);
FORCEPROP 1 LAST PATH I77
J 0
(-3100 1425);
DISPLAY 0.872340 (-3100 1425);
PAINT AQUA (-3100 1425);
DISPLAY INVISIBLE (-3100 1425);
FORCEPROP 2 LAST CDS_LIB mstr_symbols
J 0
(-3175 1425);
PAINT ORANGE (-3175 1425);
DISPLAY INVISIBLE (-3175 1425);
FORCEPROP 1 LAST SIZE 1B
J 0
(-3100 1375);
DISPLAY 0.872340 (-3100 1375);
PAINT AQUA (-3100 1375);
DISPLAY INVISIBLE (-3100 1375);
FORCEPROP 1 LAST BODY_TYPE PLUMBING
J 0
(-3220 1382);
DISPLAY 0.340426 (-3220 1382);
PAINT GREEN (-3220 1382);
DISPLAY INVISIBLE (-3220 1382);
FORCEPROP 1 LAST HDL_POWER GND
J 0
(-3175 1575);
DISPLAY 0.872340 (-3175 1575);
PAINT GREEN (-3175 1575);
DISPLAY INVISIBLE (-3175 1575);
FORCEADD OFFPAGE..1
(-6050 2675);
FORCEPROP 2 LAST $XR3 121 
J 0
(-6662 2675);
DISPLAY 0.638298 (-6662 2675);
PAINT MONO (-6662 2675);
FORCEPROP 2 LAST $XR2 150 
J 0
(-6542 2675);
DISPLAY 0.638298 (-6542 2675);
PAINT MONO (-6542 2675);
FORCEPROP 2 LAST $XR1 147 
J 0
(-6422 2675);
DISPLAY 0.638298 (-6422 2675);
PAINT MONO (-6422 2675);
FORCEPROP 2 LAST $XR0 139 
J 0
(-6302 2675);
DISPLAY 0.638298 (-6302 2675);
PAINT MONO (-6302 2675);
FORCEPROP 2 LAST CDS_LIB mstr_standard
J 0
(-6050 2675);
PAINT ORANGE (-6050 2675);
DISPLAY INVISIBLE (-6050 2675);
FORCEPROP 2 LAST PATH I84
J 0
(-6000 2750);
DISPLAY 1.021277 (-6000 2750);
PAINT ORANGE (-6000 2750);
DISPLAY INVISIBLE (-6000 2750);
FORCEPROP 1 LAST OFFPAGE TRUE
J 0
(-5725 2550);
DISPLAY 0.872340 (-5725 2550);
PAINT GREEN (-5725 2550);
DISPLAY INVISIBLE (-5725 2550);
FORCEPROP 1 LAST COMMENT_BODY TRUE
J 0
(-5925 2575);
DISPLAY 0.872340 (-5925 2575);
PAINT GREEN (-5925 2575);
DISPLAY INVISIBLE (-5925 2575);
FORCEADD OFFPAGE..3
(-725 2125);
FORCEPROP 2 LAST $XR0 116 
J 0
(-511 2125);
DISPLAY 0.638298 (-511 2125);
PAINT MONO (-511 2125);
FORCEPROP 1 LAST COMMENT_BODY TRUE
J 0
(-775 2025);
DISPLAY 0.872340 (-775 2025);
PAINT GREEN (-775 2025);
DISPLAY INVISIBLE (-775 2025);
FORCEPROP 1 LAST OFFPAGE TRUE
J 0
(-400 2000);
DISPLAY 0.872340 (-400 2000);
PAINT GREEN (-400 2000);
DISPLAY INVISIBLE (-400 2000);
FORCEPROP 2 LAST PATH I85
J 0
(-525 2200);
DISPLAY 1.021277 (-525 2200);
PAINT ORANGE (-525 2200);
DISPLAY INVISIBLE (-525 2200);
FORCEPROP 2 LAST CDS_LIB mstr_standard
J 0
(-725 2125);
PAINT ORANGE (-725 2125);
DISPLAY INVISIBLE (-725 2125);
FORCEADD OFFPAGE..3
(-725 2075);
FORCEPROP 2 LAST $XR0 116 
J 0
(-511 2075);
DISPLAY 0.638298 (-511 2075);
PAINT MONO (-511 2075);
FORCEPROP 1 LAST COMMENT_BODY TRUE
J 0
(-775 1975);
DISPLAY 0.872340 (-775 1975);
PAINT GREEN (-775 1975);
DISPLAY INVISIBLE (-775 1975);
FORCEPROP 1 LAST OFFPAGE TRUE
J 0
(-400 1950);
DISPLAY 0.872340 (-400 1950);
PAINT GREEN (-400 1950);
DISPLAY INVISIBLE (-400 1950);
FORCEPROP 2 LAST PATH I86
J 0
(-525 2150);
DISPLAY 1.021277 (-525 2150);
PAINT ORANGE (-525 2150);
DISPLAY INVISIBLE (-525 2150);
FORCEPROP 2 LAST CDS_LIB mstr_standard
J 0
(-725 2075);
PAINT ORANGE (-725 2075);
DISPLAY INVISIBLE (-725 2075);
FORCEADD CAP_A..2
(-1650 2075);
FORCEPROP 1 LASTPIN (-1750 2075) $PN 1
J 0
(-1760 2090);
DISPLAY 0.617021 (-1760 2090);
PAINT ORANGE (-1760 2090);
FORCEPROP 1 LAST MATERIAL X7R
J 0
(-1400 2000);
DISPLAY 0.617021 (-1400 2000);
PAINT SKYBLUE (-1400 2000);
FORCEPROP 1 LAST PACK_TYPE 0402V
J 1
(-1400 1950);
DISPLAY 0.617021 (-1400 1950);
PAINT SKYBLUE (-1400 1950);
FORCEPROP 1 LAST TOLERANCE 10%
J 2
(-1450 2000);
DISPLAY 0.617021 (-1450 2000);
PAINT SKYBLUE (-1450 2000);
FORCEPROP 1 LAST PART_NUMBER A36096-030
J 1
(-1650 1950);
DISPLAY 0.617021 (-1650 1950);
PAINT BLUE (-1650 1950);
FORCEPROP 1 LAST VALUE 0.1UF
J 2
(-1625 2000);
DISPLAY 0.617021 (-1625 2000);
PAINT SKYBLUE (-1625 2000);
FORCEPROP 1 LASTPIN (-1550 2075) $PN 2
J 0
(-1565 2090);
DISPLAY 0.617021 (-1565 2090);
PAINT ORANGE (-1565 2090);
FORCEPROP 1 LAST LOCATION C9E5
J 1
(-1875 2000);
DISPLAY 0.617021 (-1875 2000);
PAINT AQUA (-1875 2000);
FORCEPROP 0 LAST GROUP NI_I210&RJ45
J 0
(-1294 2038);
DISPLAY 0.638298 (-1294 2038);
PAINT BROWN (-1294 2038);
DISPLAY BOTH (-1294 2038);
FORCEPROP 1 LAST VOLTAGE 16V
J 0
(-1950 1950);
DISPLAY 0.617021 (-1950 1950);
PAINT SKYBLUE (-1950 1950);
FORCEPROP 2 LAST CDS_LIB dev_discrete
J 0
(-1650 2075);
PAINT ORANGE (-1650 2075);
DISPLAY INVISIBLE (-1650 2075);
FORCEPROP 2 LAST ROOM NIC_SPRV
J 0
(-1650 2250);
DISPLAY 1.021277 (-1650 2250);
PAINT ORANGE (-1650 2250);
DISPLAY INVISIBLE (-1650 2250);
FORCEPROP 2 LAST BOM_COST NT_GBE_BASE
J 0
(-1650 2300);
DISPLAY 1.021277 (-1650 2300);
PAINT ORANGE (-1650 2300);
DISPLAY INVISIBLE (-1650 2300);
FORCEPROP 1 LAST PATH I87
J 0
(-1650 2275);
DISPLAY 0.978723 (-1650 2275);
PAINT WHITE (-1650 2275);
DISPLAY INVISIBLE (-1650 2275);
FORCEPROP 2 LAST SEC 1
J 0
(-1650 2325);
DISPLAY 0.680851 (-1650 2325);
PAINT MONO (-1650 2325);
DISPLAY INVISIBLE (-1650 2325);
FORCEPROP 2 LAST SEC_TYPE 0402V
J 0
(-1650 2325);
DISPLAY 1.021277 (-1650 2325);
PAINT ORANGE (-1650 2325);
DISPLAY INVISIBLE (-1650 2325);
FORCEPROP 2 LAST CDS_SEC 1
J 0
(-1450 2125);
PAINT ORANGE (-1450 2125);
DISPLAY INVISIBLE (-1450 2125);
FORCEPROP 2 LAST CDS_LOCATION C9E5
J 1
(-1450 2075);
DISPLAY 0.617021 (-1450 2075);
PAINT AQUA (-1450 2075);
DISPLAY INVISIBLE (-1450 2075);
FORCEADD CAP_A..2
(-2400 2125);
FORCEPROP 1 LASTPIN (-2300 2125) $PN 2
J 0
(-2315 2140);
DISPLAY 0.617021 (-2315 2140);
PAINT ORANGE (-2315 2140);
FORCEPROP 1 LASTPIN (-2500 2125) $PN 1
J 0
(-2510 2140);
DISPLAY 0.617021 (-2510 2140);
PAINT ORANGE (-2510 2140);
FORCEPROP 1 LAST VOLTAGE 16V
J 0
(-2650 2000);
DISPLAY 0.617021 (-2650 2000);
PAINT SKYBLUE (-2650 2000);
FORCEPROP 1 LAST PART_NUMBER A36096-030
J 1
(-2400 1975);
DISPLAY 0.617021 (-2400 1975);
PAINT BLUE (-2400 1975);
FORCEPROP 1 LAST MATERIAL X7R
J 0
(-2175 2050);
DISPLAY 0.617021 (-2175 2050);
PAINT SKYBLUE (-2175 2050);
FORCEPROP 1 LAST PACK_TYPE 0402V
J 1
(-2150 2000);
DISPLAY 0.617021 (-2150 2000);
PAINT SKYBLUE (-2150 2000);
FORCEPROP 1 LAST LOCATION C9E4
J 1
(-2600 2050);
DISPLAY 0.617021 (-2600 2050);
PAINT AQUA (-2600 2050);
FORCEPROP 1 LAST TOLERANCE 10%
J 2
(-2225 2050);
DISPLAY 0.617021 (-2225 2050);
PAINT SKYBLUE (-2225 2050);
FORCEPROP 1 LAST VALUE 0.1UF
J 2
(-2375 2050);
DISPLAY 0.617021 (-2375 2050);
PAINT SKYBLUE (-2375 2050);
FORCEPROP 0 LAST GROUP NI_I210&RJ45
J 0
(-2244 2138);
DISPLAY 0.638298 (-2244 2138);
PAINT BROWN (-2244 2138);
DISPLAY BOTH (-2244 2138);
FORCEPROP 2 LAST CDS_LIB dev_discrete
J 0
(-2400 2125);
PAINT ORANGE (-2400 2125);
DISPLAY INVISIBLE (-2400 2125);
FORCEPROP 2 LAST ROOM NIC_SPRV
J 0
(-2400 2275);
DISPLAY 1.021277 (-2400 2275);
PAINT ORANGE (-2400 2275);
DISPLAY INVISIBLE (-2400 2275);
FORCEPROP 1 LAST PATH I88
J 0
(-2400 2325);
DISPLAY 0.978723 (-2400 2325);
PAINT WHITE (-2400 2325);
DISPLAY INVISIBLE (-2400 2325);
FORCEPROP 2 LAST BOM_COST NT_GBE_BASE
J 0
(-2400 2325);
DISPLAY 1.021277 (-2400 2325);
PAINT ORANGE (-2400 2325);
DISPLAY INVISIBLE (-2400 2325);
FORCEPROP 2 LAST SEC 1
J 0
(-2400 2375);
DISPLAY 0.680851 (-2400 2375);
PAINT MONO (-2400 2375);
DISPLAY INVISIBLE (-2400 2375);
FORCEPROP 2 LAST SEC_TYPE 0402V
J 0
(-2400 2375);
DISPLAY 1.021277 (-2400 2375);
PAINT ORANGE (-2400 2375);
DISPLAY INVISIBLE (-2400 2375);
FORCEPROP 2 LAST CDS_LOCATION C9E4
J 1
(-2200 2125);
DISPLAY 0.617021 (-2200 2125);
PAINT AQUA (-2200 2125);
DISPLAY INVISIBLE (-2200 2125);
FORCEPROP 2 LAST CDS_SEC 1
J 0
(-2200 2175);
PAINT ORANGE (-2200 2175);
DISPLAY INVISIBLE (-2200 2175);
FORCEADD CAP_A..2
(-5925 2125);
FORCEPROP 1 LAST VALUE 0.1UF
J 2
(-5925 2025);
DISPLAY 0.617021 (-5925 2025);
PAINT SKYBLUE (-5925 2025);
FORCEPROP 1 LASTPIN (-6025 2125) $PN 1
J 0
(-6035 2140);
DISPLAY 0.617021 (-6035 2140);
PAINT ORANGE (-6035 2140);
FORCEPROP 1 LAST TOLERANCE 10%
J 2
(-5925 1975);
DISPLAY 0.617021 (-5925 1975);
PAINT SKYBLUE (-5925 1975);
FORCEPROP 1 LAST PACK_TYPE 0402V
J 1
(-5925 1925);
DISPLAY 0.617021 (-5925 1925);
PAINT SKYBLUE (-5925 1925);
FORCEPROP 1 LAST MATERIAL X7R
J 0
(-5925 1975);
DISPLAY 0.617021 (-5925 1975);
PAINT SKYBLUE (-5925 1975);
FORCEPROP 1 LAST VOLTAGE 16V
J 0
(-5925 2025);
DISPLAY 0.617021 (-5925 2025);
PAINT SKYBLUE (-5925 2025);
FORCEPROP 1 LAST LOCATION C2M23
J 1
(-5900 2225);
DISPLAY 0.617021 (-5900 2225);
PAINT AQUA (-5900 2225);
FORCEPROP 1 LASTPIN (-5825 2125) $PN 2
J 0
(-5840 2140);
DISPLAY 0.617021 (-5840 2140);
PAINT ORANGE (-5840 2140);
FORCEPROP 1 LAST PART_NUMBER A36096-030
J 1
(-5925 2175);
DISPLAY 0.617021 (-5925 2175);
PAINT BLUE (-5925 2175);
FORCEPROP 0 LAST GROUP NI_I210&RJ45
J 0
(-6044 1888);
DISPLAY 0.638298 (-6044 1888);
PAINT BROWN (-6044 1888);
DISPLAY BOTH (-6044 1888);
FORCEPROP 2 LAST SEC 1
J 0
(-5925 2375);
DISPLAY 0.680851 (-5925 2375);
PAINT MONO (-5925 2375);
DISPLAY INVISIBLE (-5925 2375);
FORCEPROP 2 LAST SEC_TYPE 0402V
J 0
(-5925 2375);
DISPLAY 1.021277 (-5925 2375);
PAINT ORANGE (-5925 2375);
DISPLAY INVISIBLE (-5925 2375);
FORCEPROP 1 LAST PATH I89
J 0
(-5925 2325);
DISPLAY 0.978723 (-5925 2325);
PAINT WHITE (-5925 2325);
DISPLAY INVISIBLE (-5925 2325);
FORCEPROP 2 LAST BOM_COST NT_GBE_BASE
J 0
(-5900 2325);
DISPLAY 1.021277 (-5900 2325);
PAINT ORANGE (-5900 2325);
DISPLAY INVISIBLE (-5900 2325);
FORCEPROP 2 LAST ROOM NIC_SPRV
J 0
(-5900 2275);
DISPLAY 1.021277 (-5900 2275);
PAINT ORANGE (-5900 2275);
DISPLAY INVISIBLE (-5900 2275);
FORCEPROP 2 LAST CDS_SEC 1
J 0
(-5900 2275);
PAINT ORANGE (-5900 2275);
DISPLAY INVISIBLE (-5900 2275);
FORCEPROP 2 LAST CDS_LIB dev_discrete
J 0
(-5925 2125);
PAINT ORANGE (-5925 2125);
DISPLAY INVISIBLE (-5925 2125);
FORCEPROP 2 LAST CDS_LOCATION C2M23
J 1
(-5900 2225);
DISPLAY 0.617021 (-5900 2225);
PAINT AQUA (-5900 2225);
DISPLAY INVISIBLE (-5900 2225);
FORCEADD CAP_A..2
(-6150 2075);
FORCEPROP 1 LAST LOCATION C2M24
J 1
(-6150 2175);
DISPLAY 0.617021 (-6150 2175);
PAINT AQUA (-6150 2175);
FORCEPROP 1 LAST PART_NUMBER A36096-030
J 1
(-6150 2125);
DISPLAY 0.617021 (-6150 2125);
PAINT BLUE (-6150 2125);
FORCEPROP 1 LAST VOLTAGE 16V
J 0
(-6150 1975);
DISPLAY 0.617021 (-6150 1975);
PAINT SKYBLUE (-6150 1975);
FORCEPROP 1 LAST MATERIAL X7R
J 0
(-6150 1925);
DISPLAY 0.617021 (-6150 1925);
PAINT SKYBLUE (-6150 1925);
FORCEPROP 1 LAST PACK_TYPE 0402V
J 1
(-6150 1875);
DISPLAY 0.617021 (-6150 1875);
PAINT SKYBLUE (-6150 1875);
FORCEPROP 1 LASTPIN (-6250 2075) $PN 1
J 0
(-6260 2090);
DISPLAY 0.617021 (-6260 2090);
PAINT ORANGE (-6260 2090);
FORCEPROP 1 LAST VALUE 0.1UF
J 2
(-6150 1975);
DISPLAY 0.617021 (-6150 1975);
PAINT SKYBLUE (-6150 1975);
FORCEPROP 1 LASTPIN (-6050 2075) $PN 2
J 0
(-6065 2090);
DISPLAY 0.617021 (-6065 2090);
PAINT ORANGE (-6065 2090);
FORCEPROP 1 LAST TOLERANCE 10%
J 2
(-6150 1925);
DISPLAY 0.617021 (-6150 1925);
PAINT SKYBLUE (-6150 1925);
FORCEPROP 0 LAST GROUP NI_I210&RJ45
J 0
(-6269 1838);
DISPLAY 0.638298 (-6269 1838);
PAINT BROWN (-6269 1838);
DISPLAY BOTH (-6269 1838);
FORCEPROP 2 LAST SEC_TYPE 0402V
J 0
(-6150 2325);
DISPLAY 1.021277 (-6150 2325);
PAINT ORANGE (-6150 2325);
DISPLAY INVISIBLE (-6150 2325);
FORCEPROP 2 LAST SEC 1
J 0
(-6150 2325);
DISPLAY 0.680851 (-6150 2325);
PAINT MONO (-6150 2325);
DISPLAY INVISIBLE (-6150 2325);
FORCEPROP 2 LAST BOM_COST NT_GBE_BASE
J 0
(-6150 2275);
DISPLAY 1.021277 (-6150 2275);
PAINT ORANGE (-6150 2275);
DISPLAY INVISIBLE (-6150 2275);
FORCEPROP 1 LAST PATH I90
J 0
(-6150 2275);
DISPLAY 0.978723 (-6150 2275);
PAINT WHITE (-6150 2275);
DISPLAY INVISIBLE (-6150 2275);
FORCEPROP 2 LAST CDS_SEC 1
J 0
(-6150 2225);
PAINT ORANGE (-6150 2225);
DISPLAY INVISIBLE (-6150 2225);
FORCEPROP 2 LAST CDS_LIB dev_discrete
J 0
(-6150 2075);
PAINT ORANGE (-6150 2075);
DISPLAY INVISIBLE (-6150 2075);
FORCEPROP 2 LAST CDS_LOCATION C2M24
J 1
(-6150 2175);
DISPLAY 0.617021 (-6150 2175);
PAINT AQUA (-6150 2175);
DISPLAY INVISIBLE (-6150 2175);
FORCEPROP 2 LAST ROOM NIC_SPRV
J 0
(-6150 2225);
DISPLAY 1.021277 (-6150 2225);
PAINT ORANGE (-6150 2225);
DISPLAY INVISIBLE (-6150 2225);
FORCEADD OFFPAGE..6
(-6900 2075);
FORCEPROP 2 LAST $XR0 116 
J 0
(-7210 2075);
DISPLAY 0.638298 (-7210 2075);
PAINT MONO (-7210 2075);
FORCEPROP 1 LAST COMMENT_BODY TRUE
J 0
(-6800 2000);
DISPLAY 0.872340 (-6800 2000);
PAINT GREEN (-6800 2000);
DISPLAY INVISIBLE (-6800 2000);
FORCEPROP 1 LAST OFFPAGE TRUE
J 0
(-6575 1950);
DISPLAY 0.872340 (-6575 1950);
PAINT GREEN (-6575 1950);
DISPLAY INVISIBLE (-6575 1950);
FORCEPROP 2 LAST PATH I91
J 0
(-6850 2150);
DISPLAY 1.021277 (-6850 2150);
PAINT ORANGE (-6850 2150);
DISPLAY INVISIBLE (-6850 2150);
FORCEPROP 2 LAST CDS_LIB mstr_standard
J 0
(-6900 2075);
PAINT ORANGE (-6900 2075);
DISPLAY INVISIBLE (-6900 2075);
FORCEADD OFFPAGE..6
(-6900 2125);
FORCEPROP 2 LAST $XR0 116 
J 0
(-7210 2125);
DISPLAY 0.638298 (-7210 2125);
PAINT MONO (-7210 2125);
FORCEPROP 1 LAST COMMENT_BODY TRUE
J 0
(-6800 2050);
DISPLAY 0.872340 (-6800 2050);
PAINT GREEN (-6800 2050);
DISPLAY INVISIBLE (-6800 2050);
FORCEPROP 1 LAST OFFPAGE TRUE
J 0
(-6575 2000);
DISPLAY 0.872340 (-6575 2000);
PAINT GREEN (-6575 2000);
DISPLAY INVISIBLE (-6575 2000);
FORCEPROP 2 LAST PATH I92
J 0
(-6850 2200);
DISPLAY 1.021277 (-6850 2200);
PAINT ORANGE (-6850 2200);
DISPLAY INVISIBLE (-6850 2200);
FORCEPROP 2 LAST CDS_LIB mstr_standard
J 0
(-6900 2125);
PAINT ORANGE (-6900 2125);
DISPLAY INVISIBLE (-6900 2125);
FORCEADD OFFPAGE..1
(-6900 1975);
FORCEPROP 2 LAST $XR0 114 
J 0
(-7152 1975);
DISPLAY 0.638298 (-7152 1975);
PAINT MONO (-7152 1975);
FORCEPROP 1 LAST COMMENT_BODY TRUE
J 0
(-6775 1875);
DISPLAY 0.872340 (-6775 1875);
PAINT GREEN (-6775 1875);
DISPLAY INVISIBLE (-6775 1875);
FORCEPROP 1 LAST OFFPAGE TRUE
J 0
(-6575 1850);
DISPLAY 0.872340 (-6575 1850);
PAINT GREEN (-6575 1850);
DISPLAY INVISIBLE (-6575 1850);
FORCEPROP 2 LAST PATH I93
J 0
(-6850 2050);
DISPLAY 1.021277 (-6850 2050);
PAINT ORANGE (-6850 2050);
DISPLAY INVISIBLE (-6850 2050);
FORCEPROP 2 LAST CDS_LIB mstr_standard
J 0
(-6900 1975);
PAINT ORANGE (-6900 1975);
DISPLAY INVISIBLE (-6900 1975);
FORCEADD OFFPAGE..1
(-6900 1925);
FORCEPROP 2 LAST $XR0 114 
J 0
(-7152 1925);
DISPLAY 0.638298 (-7152 1925);
PAINT MONO (-7152 1925);
FORCEPROP 1 LAST COMMENT_BODY TRUE
J 0
(-6775 1825);
DISPLAY 0.872340 (-6775 1825);
PAINT GREEN (-6775 1825);
DISPLAY INVISIBLE (-6775 1825);
FORCEPROP 1 LAST OFFPAGE TRUE
J 0
(-6575 1800);
DISPLAY 0.872340 (-6575 1800);
PAINT GREEN (-6575 1800);
DISPLAY INVISIBLE (-6575 1800);
FORCEPROP 2 LAST PATH I94
J 0
(-6850 2000);
DISPLAY 1.021277 (-6850 2000);
PAINT ORANGE (-6850 2000);
DISPLAY INVISIBLE (-6850 2000);
FORCEPROP 2 LAST CDS_LIB mstr_standard
J 0
(-6900 1925);
PAINT ORANGE (-6900 1925);
DISPLAY INVISIBLE (-6900 1925);
FORCEADD DNS..2
(-1595 870);
PAINT RED (-1595 870);
FORCEPROP 2 LAST CDS_LIB mstr_misc
J 0
(-1595 870);
PAINT ORANGE (-1595 870);
DISPLAY INVISIBLE (-1595 870);
FORCEPROP 1 LAST COMMENT_BODY TRUE
R 1
J 0
(-1520 645);
DISPLAY 0.872340 (-1520 645);
PAINT GREEN (-1520 645);
DISPLAY INVISIBLE (-1520 645);
FORCEADD CAD_NOTE..1
(-2400 1350);
FORCEPROP 0 LAST L1 PLACE THIS RESISTOR
J 0
(-2550 1250);
DISPLAY 0.808511 (-2550 1250);
PAINT ORANGE (-2550 1250);
FORCEPROP 0 LAST L2 NEAR PCH
J 0
(-2550 1200);
DISPLAY 0.808511 (-2550 1200);
PAINT ORANGE (-2550 1200);
FORCEPROP 1 LAST COMMENT_BODY TRUE
J 0
(-2375 1450);
DISPLAY 0.978723 (-2375 1450);
PAINT ORANGE (-2375 1450);
DISPLAY INVISIBLE (-2375 1450);
FORCEPROP 2 LAST CDS_LIB mstr_symbols
J 0
(-2400 1350);
PAINT ORANGE (-2400 1350);
DISPLAY INVISIBLE (-2400 1350);
FORCEADD CAD_NOTE..1
(-5650 1650);
FORCEPROP 0 LAST L1 PLACE THESE CAPS NEAR PCH
J 0
(-5800 1550);
DISPLAY 0.808511 (-5800 1550);
PAINT ORANGE (-5800 1550);
FORCEPROP 2 LAST CDS_LIB mstr_symbols
J 0
(-5650 1650);
PAINT ORANGE (-5650 1650);
DISPLAY INVISIBLE (-5650 1650);
FORCEPROP 1 LAST COMMENT_BODY TRUE
J 0
(-5625 1750);
DISPLAY 0.978723 (-5625 1750);
PAINT ORANGE (-5625 1750);
DISPLAY INVISIBLE (-5625 1750);
FORCEADD DESIGN_NOTE..1
(-7700 4450);
FORCEPROP 0 LAST L5 DEFAULT CONFIG IS FOR -AT SKU
J 0
(-7900 4100);
DISPLAY 0.638298 (-7900 4100);
PAINT ORANGE (-7900 4100);
FORCEPROP 0 LAST L4 DE-POP R1T34
J 0
(-7900 4200);
DISPLAY 0.638298 (-7900 4200);
PAINT ORANGE (-7900 4200);
FORCEPROP 0 LAST L3 STUFF R1T33
J 0
(-7900 4250);
DISPLAY 0.638298 (-7900 4250);
PAINT ORANGE (-7900 4250);
FORCEPROP 0 LAST L2 DE-POP R1T32
J 0
(-7900 4300);
DISPLAY 0.638298 (-7900 4300);
PAINT ORANGE (-7900 4300);
FORCEPROP 0 LAST L1 FOR -IS SKU:
J 0
(-7900 4350);
DISPLAY 0.638298 (-7900 4350);
PAINT ORANGE (-7900 4350);
FORCEPROP 2 LAST CDS_LIB mstr_symbols
J 0
(-7700 4450);
PAINT ORANGE (-7700 4450);
DISPLAY INVISIBLE (-7700 4450);
FORCEPROP 1 LAST COMMENT_BODY TRUE
J 0
(-7675 4550);
DISPLAY 0.978723 (-7675 4550);
PAINT ORANGE (-7675 4550);
DISPLAY INVISIBLE (-7675 4550);
FORCEADD DNS..2
(-5795 3720);
PAINT RED (-5795 3720);
FORCEPROP 1 LAST COMMENT_BODY TRUE
R 1
J 0
(-5720 3495);
DISPLAY 0.872340 (-5720 3495);
PAINT GREEN (-5720 3495);
DISPLAY INVISIBLE (-5720 3495);
FORCEPROP 2 LAST CDS_LIB mstr_misc
J 0
(-5795 3720);
PAINT ORANGE (-5795 3720);
DISPLAY INVISIBLE (-5795 3720);
FORCEADD INTEL_CORP_BPAGE..1
(50 25);
FORCEPROP 1 LAST CDS_CON_LAST_MODIFIED Fri Jun 16 17:48:52 2017
J 0
(-1075 550);
DISPLAY 2.659574 (-1075 550);
PAINT GREEN (-1075 550);
DISPLAY INVISIBLE (-1075 550);
FORCEPROP 1 LAST CUSTOM_TXT_CDS <CURRENT_DESIGN_SHEET> OF <TOTAL_DESIGN_SHEETS>
J 0
(-450 50);
PAINT ORANGE (-450 50);
FORCEPROP 2 LAST CUSTOM_TXT_CDS <XR_PAGE_TITLE>
J 0
(-7840 5275);
DISPLAY 0.638298 (-7840 5275);
PAINT PINK (-7840 5275);
DISPLAY INVISIBLE (-7840 5275);
FORCEPROP 2 LAST CUSTOM_TXT_CDS <CON_LAST_MODIFIED>
J 0
(-3950 125);
DISPLAY 0.957447 (-3950 125);
PAINT ORANGE (-3950 125);
FORCEPROP 1 LAST SCH_TITLE LAN SPRINGVILLE I210 (1/3)
J 0
(-7900 75);
DISPLAY 1.212766 (-7900 75);
PAINT GREEN (-7900 75);
FORCEPROP 2 LAST PAGE_BORDER TRUE
J 0
(-7840 5275);
DISPLAY 0.425532 (-7840 5275);
PAINT PINK (-7840 5275);
DISPLAY INVISIBLE (-7840 5275);
FORCEPROP 2 LAST CDS_LIB mstr_symbols
J 0
(50 25);
DISPLAY 0.489362 (50 25);
PAINT ORANGE (50 25);
DISPLAY INVISIBLE (50 25);
FORCEPROP 1 LAST COMMENT_BODY TRUE
J 0
(62 37);
DISPLAY 0.319149 (62 37);
PAINT GREEN (62 37);
DISPLAY INVISIBLE (62 37);
FORCEPROP 2 LAST CDS_XR_PAGE_TITLE CR-139 : @BASEBOARD_FAB2_LIB.BASEBOARD_FAB2(SCH_1):PAGE139
J 0
(-7840 5275);
DISPLAY 0.638298 (-7840 5275);
PAINT PINK (-7840 5275);
DISPLAY INVISIBLE (-7840 5275);
FORCEADD CAD_NOTE..1
(-4375 1575);
FORCEPROP 0 LAST L2 NEAR THE BMC
J 0
(-4525 1400);
DISPLAY 0.808511 (-4525 1400);
PAINT ORANGE (-4525 1400);
FORCEPROP 0 LAST L1 PLACE CAPS ON PE_PCH_SPRV_RX_DP/DN
J 0
(-4525 1475);
DISPLAY 0.808511 (-4525 1475);
PAINT ORANGE (-4525 1475);
FORCEPROP 2 LAST CDS_LIB mstr_symbols
J 0
(-4375 1575);
PAINT ORANGE (-4375 1575);
DISPLAY INVISIBLE (-4375 1575);
FORCEPROP 1 LAST COMMENT_BODY TRUE
J 0
(-4350 1675);
DISPLAY 0.978723 (-4350 1675);
PAINT ORANGE (-4350 1675);
DISPLAY INVISIBLE (-4350 1675);
FORCEADD DNS..2
(-1920 870);
PAINT RED (-1920 870);
FORCEPROP 1 LAST COMMENT_BODY TRUE
R 1
J 0
(-1845 645);
DISPLAY 0.872340 (-1845 645);
PAINT GREEN (-1845 645);
DISPLAY INVISIBLE (-1845 645);
FORCEPROP 2 LAST CDS_LIB mstr_misc
J 0
(-1920 870);
PAINT ORANGE (-1920 870);
DISPLAY INVISIBLE (-1920 870);
FORCEADD CAD_NOTE..1
(-2875 4950);
FORCEPROP 0 LAST L9 SPI_NIC_SCLK_R
J 0
(-3025 4450);
DISPLAY 0.808511 (-3025 4450);
PAINT ORANGE (-3025 4450);
FORCEPROP 0 LAST L6 RMII_SPRNGVLLE_BMC_PCH_RXD0_R
J 0
(-3025 4600);
DISPLAY 0.808511 (-3025 4600);
PAINT ORANGE (-3025 4600);
FORCEPROP 0 LAST L4 RMII_BMC_PCH_SPRNGVLLE_CRSDV_R
J 0
(-3025 4700);
DISPLAY 0.808511 (-3025 4700);
PAINT ORANGE (-3025 4700);
FORCEPROP 0 LAST L7 SPI_NIC_MOSI_R
J 0
(-3025 4550);
DISPLAY 0.808511 (-3025 4550);
PAINT ORANGE (-3025 4550);
FORCEPROP 0 LAST L8 SPI_NIC_CS_R_N
J 0
(-3025 4500);
DISPLAY 0.808511 (-3025 4500);
PAINT ORANGE (-3025 4500);
FORCEPROP 0 LAST L1 PLACE SERIES RESISTORS ON THE FOLLOWING
J 0
(-3025 4850);
DISPLAY 0.808511 (-3025 4850);
PAINT ORANGE (-3025 4850);
FORCEPROP 0 LAST L2 NETS WITHIN TWO INCHES OF SPRINGVILLE:
J 0
(-3025 4800);
DISPLAY 0.808511 (-3025 4800);
PAINT ORANGE (-3025 4800);
FORCEPROP 0 LAST L3 RMII_PCH_SPRNGVLLE_ARB_IN_R
J 0
(-3025 4750);
DISPLAY 0.808511 (-3025 4750);
PAINT ORANGE (-3025 4750);
FORCEPROP 0 LAST L5 RMII_SPNGVLLE_BMC-PCH_RXD1_R
J 0
(-3025 4650);
DISPLAY 0.808511 (-3025 4650);
PAINT ORANGE (-3025 4650);
FORCEPROP 2 LAST CDS_LIB mstr_symbols
J 0
(-2875 4950);
PAINT ORANGE (-2875 4950);
DISPLAY INVISIBLE (-2875 4950);
FORCEPROP 1 LAST COMMENT_BODY TRUE
J 0
(-2850 5050);
DISPLAY 0.978723 (-2850 5050);
PAINT ORANGE (-2850 5050);
DISPLAY INVISIBLE (-2850 5050);
FORCEADD DESIGN_NOTE..1
(-7700 4875);
FORCEPROP 0 LAST L1 SHUNT CAPACITORS CAN BE CALCULATED USING THE FOLLOWING EQUATION
J 0
(-7900 4775);
DISPLAY 0.638298 (-7900 4775);
PAINT ORANGE (-7900 4775);
FORCEPROP 0 LAST L5 TYPICAL CSTRAY IS 3PF TO 7PF
J 0
(-7900 4575);
DISPLAY 0.638298 (-7900 4575);
PAINT ORANGE (-7900 4575);
FORCEPROP 0 LAST L2 C1 = C2 = 2 * [CLOAD-CSTRAY]
J 0
(-7900 4725);
DISPLAY 0.638298 (-7900 4725);
PAINT ORANGE (-7900 4725);
FORCEPROP 0 LAST L6 WILL NEED TO RE CALCULATE THIS VALUE WHEN LAYOUT HAS BEEN DONE
J 0
(-7900 4525);
DISPLAY 0.638298 (-7900 4525);
PAINT ORANGE (-7900 4525);
FORCEPROP 0 LAST L4 AND CSTRAY IS THE CAPACITANCE OF SOLDER PADS, TRACES AND I210 PACKAGE
J 0
(-7900 4625);
DISPLAY 0.638298 (-7900 4625);
PAINT ORANGE (-7900 4625);
FORCEPROP 0 LAST L3 WHERE CLOAD IS THE LOAD CAPACITANCE OF THE CRYSTAL (18PF FOR D71700-031)
J 0
(-7900 4675);
DISPLAY 0.638298 (-7900 4675);
PAINT ORANGE (-7900 4675);
FORCEPROP 2 LAST CDS_LIB mstr_symbols
J 0
(-7700 4875);
PAINT ORANGE (-7700 4875);
DISPLAY INVISIBLE (-7700 4875);
FORCEPROP 1 LAST COMMENT_BODY TRUE
J 0
(-7675 4975);
DISPLAY 0.978723 (-7675 4975);
PAINT ORANGE (-7675 4975);
DISPLAY INVISIBLE (-7675 4975);
WIRE 16 -1 (-7325 1100)(-7325 875);
WIRE 16 -1 (-7750 1100)(-7750 875);
WIRE 16 -1 (-6950 3550)(-6950 3650);
WIRE 16 -1 (-6375 3800)(-6375 3875);
WIRE 16 -1 (-5975 4100)(-5975 4175);
WIRE 16 -1 (-4150 1050)(-4150 1150);
WIRE 16 -1 (-4150 1050)(-4000 1050);
WIRE 16 -1 (-4000 1050)(-3700 1050);
WIRE 16 -1 (-4000 875)(-4000 1050);
WIRE 16 -1 (-3325 1050)(-3700 1050);
WIRE 16 -1 (-3700 1050)(-3700 875);
WIRE 16 -1 (-3075 1050)(-3325 1050);
WIRE 16 -1 (-3325 1050)(-3325 975);
WIRE 16 -1 (-2825 1050)(-3075 1050);
WIRE 16 -1 (-3075 1050)(-3075 975);
WIRE 16 -1 (-2575 1050)(-2825 1050);
WIRE 16 -1 (-2825 1050)(-2825 975);
WIRE 16 -1 (-2325 1050)(-2575 1050);
WIRE 16 -1 (-2575 1050)(-2575 975);
WIRE 16 -1 (-2325 975)(-2325 1050);
WIRE 16 -1 (-1925 1050)(-1925 1100);
WIRE 16 -1 (-1925 1050)(-1600 1050);
WIRE 16 -1 (-1925 1050)(-1925 975);
WIRE 16 -1 (-1350 1050)(-1600 1050);
WIRE 16 -1 (-1600 975)(-1600 1050);
WIRE 16 -1 (-1100 1050)(-1350 1050);
WIRE 16 -1 (-1350 1050)(-1350 975);
WIRE 16 -1 (-850 1050)(-1100 1050);
WIRE 16 -1 (-1100 1050)(-1100 975);
WIRE 16 -1 (-600 1050)(-850 1050);
WIRE 16 -1 (-850 1050)(-850 975);
WIRE 16 -1 (-350 1050)(-600 1050);
WIRE 16 -1 (-600 1050)(-600 975);
WIRE 16 -1 (-350 975)(-350 1050);
WIRE 16 -1 (-1925 675)(-1925 625);
WIRE 16 -1 (-1925 675)(-1600 675);
WIRE 16 -1 (-1925 775)(-1925 675);
WIRE 16 -1 (-1350 675)(-1600 675);
WIRE 16 -1 (-1600 675)(-1600 775);
WIRE 16 -1 (-1100 675)(-1350 675);
WIRE 16 -1 (-1350 675)(-1350 775);
WIRE 16 -1 (-850 675)(-1100 675);
WIRE 16 -1 (-1100 675)(-1100 775);
WIRE 16 -1 (-600 675)(-850 675);
WIRE 16 -1 (-850 675)(-850 775);
WIRE 16 -1 (-350 675)(-600 675);
WIRE 16 -1 (-600 675)(-600 775);
WIRE 16 -1 (-350 775)(-350 675);
WIRE 16 -1 (-900 3125)(-900 3000);
WIRE 16 -1 (-7750 3425)(-7750 3500);
WIRE 16 -1 (-7750 3425)(-7475 3425);
WIRE 16 -1 (-7750 3225)(-7750 3425);
WIRE 16 -1 (-7475 3425)(-7200 3425);
WIRE 16 -1 (-7475 3425)(-7475 3225);
WIRE 16 -1 (-7200 3425)(-6950 3425);
WIRE 16 -1 (-7200 3225)(-7200 3425);
WIRE 16 -1 (-6950 3425)(-6950 3375);
WIRE 16 -1 (-1175 2825)(-1175 3150);
WIRE 16 -1 (-1400 2825)(-1175 2825);
WIRE 16 -1 (-6950 3950)(-6950 3900);
WIRE 16 -1 (-6450 3900)(-6950 3900);
WIRE 16 -1 (-6950 3850)(-6950 3900);
WIRE 16 -1 (-6450 3675)(-6450 3900);
WIRE 16 -1 (-6450 3675)(-6450 3625);
WIRE 16 -1 (-6450 3675)(-5100 3675);
WIRE 16 -1 (-6450 3625)(-6450 3575);
WIRE 16 -1 (-6450 3625)(-5100 3625);
WIRE 16 -1 (-6450 3525)(-6450 3575);
WIRE 16 -1 (-6450 3575)(-5100 3575);
WIRE 16 -1 (-6450 3475)(-6450 3525);
WIRE 16 -1 (-6450 3525)(-5700 3525);
WIRE 16 -1 (-6450 3475)(-5100 3475);
WIRE 16 -1 (-900 4000)(-900 3925);
WIRE 16 -1 (-6200 1050)(-6200 1150);
WIRE 16 -1 (-6100 1050)(-6200 1050);
WIRE 16 -1 (-5800 1050)(-6100 1050);
WIRE 16 -1 (-6100 900)(-6100 1050);
WIRE 16 -1 (-5450 1050)(-5800 1050);
WIRE 16 -1 (-5800 1050)(-5800 900);
WIRE 16 -1 (-5450 1050)(-5200 1050);
WIRE 16 -1 (-5450 1050)(-5450 950);
WIRE 16 -1 (-5200 1050)(-4950 1050);
WIRE 16 -1 (-5200 1050)(-5200 950);
WIRE 16 -1 (-4950 1050)(-4700 1050);
WIRE 16 -1 (-4950 1050)(-4950 950);
WIRE 16 -1 (-4700 1050)(-4450 1050);
WIRE 16 -1 (-4700 1050)(-4700 950);
WIRE 16 -1 (-4450 950)(-4450 1050);
WIRE 16 -1 (-1000 4650)(-1000 4575);
WIRE 16 -1 (-6925 750)(-6925 650);
WIRE 16 -1 (-1900 1550)(-1900 1425);
WIRE 16 -1 (-3050 1400)(-3050 1275);
WIRE 16 -1 (-1300 1450)(-1300 1400);
WIRE 16 -1 (-6100 600)(-6100 575);
WIRE 16 -1 (-5800 600)(-6100 600);
WIRE 16 -1 (-6100 750)(-6100 600);
WIRE 16 -1 (-5450 600)(-5800 600);
WIRE 16 -1 (-5800 750)(-5800 600);
WIRE 16 -1 (-5450 600)(-5200 600);
WIRE 16 -1 (-5450 600)(-5450 750);
WIRE 16 -1 (-5200 600)(-4950 600);
WIRE 16 -1 (-5200 600)(-5200 750);
WIRE 16 -1 (-4950 600)(-4700 600);
WIRE 16 -1 (-4950 750)(-4950 600);
WIRE 16 -1 (-4700 600)(-4450 600);
WIRE 16 -1 (-4700 600)(-4700 750);
WIRE 16 -1 (-4450 750)(-4450 600);
WIRE 16 -1 (-4000 575)(-4000 600);
WIRE 16 -1 (-3700 600)(-4000 600);
WIRE 16 -1 (-4000 600)(-4000 725);
WIRE 16 -1 (-3325 600)(-3700 600);
WIRE 16 -1 (-3700 725)(-3700 600);
WIRE 16 -1 (-3075 600)(-3325 600);
WIRE 16 -1 (-3325 600)(-3325 775);
WIRE 16 -1 (-2825 600)(-3075 600);
WIRE 16 -1 (-3075 600)(-3075 775);
WIRE 16 -1 (-2575 600)(-2825 600);
WIRE 16 -1 (-2825 775)(-2825 600);
WIRE 16 -1 (-2325 600)(-2575 600);
WIRE 16 -1 (-2575 600)(-2575 775);
WIRE 16 -1 (-2325 775)(-2325 600);
WIRE 16 -1 (-5725 4425)(-5725 4475);
WIRE 16 -1 (-5725 4275)(-5725 4425);
WIRE 16 -1 (-5975 4425)(-5725 4425);
WIRE 16 -1 (-5975 4375)(-5975 4425);
WIRE 16 -1 (-5725 4275)(-5725 4225);
WIRE 16 -1 (-5725 4275)(-5100 4275);
WIRE 16 -1 (-5725 4225)(-5725 4175);
WIRE 16 -1 (-5725 4225)(-5100 4225);
WIRE 16 -1 (-5725 4175)(-5725 4125);
WIRE 16 -1 (-5725 4175)(-5100 4175);
WIRE 16 -1 (-5725 4125)(-5725 4025);
WIRE 16 -1 (-5725 4125)(-5100 4125);
WIRE 16 -1 (-5725 4025)(-5700 4025);
WIRE 16 -1 (-6375 4150)(-6375 4250);
WIRE 16 -1 (-6075 4150)(-6375 4150);
FORCEPROP 0 LAST VOLTAGE +1.5V
J 0
(-6200 4200);
DISPLAY 1.021277 (-6200 4200);
PAINT SKYBLUE (-6200 4200);
DISPLAY INVISIBLE (-6200 4200);
WIRE 16 -1 (-6375 4075)(-6375 4150);
WIRE 16 -1 (-6075 3925)(-6075 4150);
WIRE 16 -1 (-6075 3875)(-6075 3925);
WIRE 16 -1 (-6075 3925)(-5100 3925);
WIRE 16 -1 (-6075 3775)(-6075 3875);
WIRE 16 -1 (-5900 3875)(-6075 3875);
WIRE 16 -1 (-6075 3725)(-6075 3775);
WIRE 16 -1 (-6075 3775)(-5100 3775);
WIRE 16 -1 (-5900 3725)(-6075 3725);
WIRE 16 -1 (-3175 1475)(-3175 1875);
WIRE 16 -1 (-3175 1875)(-3300 1875);
WIRE 16 -1 (-3300 3275)(-2400 3275);
FORCEPROP 2 LAST SIG_NAME TP_SPRV_SDP3
J 2
(-2400 3285);
DISPLAY 0.617021 (-2400 3285);
PAINT ORANGE (-2400 3285);
FORCEPROP 2 LASTPROP $XRERR UNIQUE?
J 0
(-2370 3275);
DISPLAY 0.638298 (-2370 3275);
PAINT MONO (-2370 3275);
DISPLAY INVISIBLE (-2370 3275);
WIRE 16 -1 (-750 2450)(-750 2475);
WIRE 16 -1 (-1800 2450)(-750 2450);
FORCEPROP 2 LAST SIG_NAME RMII_SPRNGVLLE_BMC_PCH_RXD0
J 2
(-925 2460);
DISPLAY 0.617021 (-925 2460);
PAINT ORANGE (-925 2460);
WIRE 16 -1 (-3300 2325)(-1950 2325);
FORCEPROP 2 LAST SIG_NAME SPI_NIC_CS_R_N
J 0
(-3210 2335);
DISPLAY 0.617021 (-3210 2335);
PAINT ORANGE (-3210 2335);
FORCEPROP 2 LASTPROP $XRERR UNIQUE?
J 0
(-3450 2335);
DISPLAY 0.638298 (-3450 2335);
PAINT MONO (-3450 2335);
DISPLAY INVISIBLE (-3450 2335);
WIRE 16 -1 (-2300 2275)(-750 2275);
FORCEPROP 2 LAST SIG_NAME SPI_NIC_SCLK
J 0
(-1210 2285);
DISPLAY 0.617021 (-1210 2285);
PAINT ORANGE (-1210 2285);
WIRE 16 -1 (-3300 2075)(-1750 2075);
FORCEPROP 2 LAST SIG_NAME PE_PCH_SPRV_RX_DN
J 0
(-3210 2085);
DISPLAY 0.617021 (-3210 2085);
PAINT ORANGE (-3210 2085);
FORCEPROP 2 LASTPROP $XRERR UNIQUE?
J 0
(-3450 2085);
DISPLAY 0.638298 (-3450 2085);
PAINT MONO (-3450 2085);
DISPLAY INVISIBLE (-3450 2085);
WIRE 16 -1 (-2300 2125)(-775 2125);
FORCEPROP 2 LAST SIG_NAME PE_PCH_SPRV_RX_C_DP
J 0
(-1335 2135);
DISPLAY 0.617021 (-1335 2135);
PAINT ORANGE (-1335 2135);
WIRE 16 -1 (-1750 2325)(-750 2325);
FORCEPROP 2 LAST SIG_NAME SPI_NIC_CS_N
J 0
(-1510 2335);
DISPLAY 0.617021 (-1510 2335);
PAINT ORANGE (-1510 2335);
WIRE 16 -1 (-1900 1825)(-1900 1750);
WIRE 16 -1 (-1900 1825)(-1050 1825);
FORCEPROP 2 LAST SIG_NAME RMII_BMC_PCH_SPRNGVLLE_TXEN
J 0
(-1885 1835);
DISPLAY 0.617021 (-1885 1835);
PAINT ORANGE (-1885 1835);
WIRE 16 -1 (-1550 2075)(-775 2075);
FORCEPROP 2 LAST SIG_NAME PE_PCH_SPRV_RX_C_DN
J 0
(-1335 2085);
DISPLAY 0.617021 (-1335 2085);
PAINT ORANGE (-1335 2085);
WIRE 16 -1 (-1300 1725)(-1300 1650);
WIRE 16 -1 (-1300 1725)(-400 1725);
FORCEPROP 2 LAST SIG_NAME RMII_BMC_PCH_SPRNGVLLE_CRSDV
J 0
(-1210 1735);
DISPLAY 0.617021 (-1210 1735);
PAINT ORANGE (-1210 1735);
WIRE 16 -1 (-2725 3375)(-3300 3375);
FORCEPROP 2 LAST SIG_NAME A_CBOT
J 0
(-3160 3385);
DISPLAY 0.617021 (-3160 3385);
PAINT ORANGE (-3160 3385);
FORCEPROP 2 LASTPROP $XRERR UNIQUE?
J 0
(-3400 3385);
DISPLAY 0.638298 (-3400 3385);
PAINT MONO (-3400 3385);
DISPLAY INVISIBLE (-3400 3385);
WIRE 16 -1 (-2725 3400)(-2725 3375);
WIRE 16 -1 (-3300 3225)(-2400 3225);
FORCEPROP 2 LAST SIG_NAME TP_SPRV_SDP2
J 2
(-2400 3235);
DISPLAY 0.617021 (-2400 3235);
PAINT ORANGE (-2400 3235);
FORCEPROP 2 LASTPROP $XRERR UNIQUE?
J 0
(-2370 3225);
DISPLAY 0.638298 (-2370 3225);
PAINT MONO (-2370 3225);
DISPLAY INVISIBLE (-2370 3225);
WIRE 16 -1 (-3300 3175)(-2400 3175);
FORCEPROP 2 LAST SIG_NAME FM_1GB_LOM_DISABLE_N
J 0
(-2975 3185);
DISPLAY 0.617021 (-2975 3185);
PAINT ORANGE (-2975 3185);
WIRE 16 -1 (-3300 3125)(-2400 3125);
FORCEPROP 2 LAST SIG_NAME TP_SPRV_SDP0
J 2
(-2400 3135);
DISPLAY 0.617021 (-2400 3135);
PAINT ORANGE (-2400 3135);
FORCEPROP 2 LASTPROP $XRERR UNIQUE?
J 0
(-2370 3125);
DISPLAY 0.638298 (-2370 3125);
PAINT MONO (-2370 3125);
DISPLAY INVISIBLE (-2370 3125);
WIRE 16 -1 (-7750 1475)(-7750 1300);
WIRE 16 -1 (-7750 1475)(-7625 1475);
WIRE 16 -1 (-7750 1675)(-7750 1475);
WIRE 16 -1 (-6900 1675)(-7750 1675);
FORCEPROP 2 LAST SIG_NAME XTAL_25MHZ_IN
J 0
(-7735 1685);
DISPLAY 0.617021 (-7735 1685);
PAINT ORANGE (-7735 1685);
FORCEPROP 2 LASTPROP $XRERR UNIQUE?
J 0
(-7975 1685);
DISPLAY 0.638298 (-7975 1685);
PAINT MONO (-7975 1685);
DISPLAY INVISIBLE (-7975 1685);
WIRE 16 -1 (-6950 3125)(-6950 3175);
WIRE 16 -1 (-5100 3125)(-6950 3125);
FORCEPROP 2 LAST SIG_NAME PU_DEV_OFF_N
J 0
(-5885 3135);
DISPLAY 0.638298 (-5885 3135);
PAINT ORANGE (-5885 3135);
FORCEPROP 2 LASTPROP $XRERR UNIQUE?
J 0
(-6125 3135);
DISPLAY 0.638298 (-6125 3135);
PAINT MONO (-6125 3135);
DISPLAY INVISIBLE (-6125 3135);
WIRE 3 682 (-7025 3300)(-6975 3300);
WIRE 3 682 (-7025 3300)(-7025 3725);
WIRE 3 682 (-7025 3725)(-7075 3725);
WIRE 16 -1 (-1000 4250)(-475 4250);
FORCEPROP 2 LAST SIG_NAME IRQ_LOM_ALERT_N
J 0
(-960 4260);
DISPLAY 0.617021 (-960 4260);
PAINT ORANGE (-960 4260);
WIRE 16 -1 (-1000 4375)(-1000 4250);
WIRE 16 -1 (-900 3400)(-900 3325);
WIRE 16 -1 (-900 3400)(-425 3400);
FORCEPROP 2 LAST SIG_NAME PD_SPRV_RSET
J 0
(-785 3410);
DISPLAY 0.617021 (-785 3410);
PAINT ORANGE (-785 3410);
WIRE 16 -1 (-2300 2375)(-750 2375);
FORCEPROP 2 LAST SIG_NAME SPI_NIC_MOSI
J 0
(-1210 2385);
DISPLAY 0.617021 (-1210 2385);
PAINT ORANGE (-1210 2385);
WIRE 16 -1 (-3300 2725)(-2175 2725);
FORCEPROP 2 LAST SIG_NAME RMII_PCH_SPRNGVLLE_ARB_IN_R
J 0
(-3225 2735);
DISPLAY 0.617021 (-3225 2735);
PAINT ORANGE (-3225 2735);
FORCEPROP 2 LASTPROP $XRERR UNIQUE?
J 0
(-3465 2735);
DISPLAY 0.638298 (-3465 2735);
PAINT MONO (-3465 2735);
DISPLAY INVISIBLE (-3465 2735);
WIRE 16 -1 (-3300 2525)(-2375 2525);
FORCEPROP 2 LAST SIG_NAME RMII_SPRNGVLLE_BMC_PCH_RXD1_R
J 0
(-3260 2535);
DISPLAY 0.617021 (-3260 2535);
PAINT ORANGE (-3260 2535);
FORCEPROP 2 LASTPROP $XRERR UNIQUE?
J 0
(-3500 2535);
DISPLAY 0.638298 (-3500 2535);
PAINT MONO (-3500 2535);
DISPLAY INVISIBLE (-3500 2535);
WIRE 16 -1 (-3300 2275)(-2500 2275);
FORCEPROP 2 LAST SIG_NAME SPI_NIC_SCLK_R
J 0
(-3210 2285);
DISPLAY 0.617021 (-3210 2285);
PAINT ORANGE (-3210 2285);
FORCEPROP 2 LASTPROP $XRERR UNIQUE?
J 0
(-3450 2285);
DISPLAY 0.638298 (-3450 2285);
PAINT MONO (-3450 2285);
DISPLAY INVISIBLE (-3450 2285);
WIRE 16 -1 (-1975 2725)(-750 2725);
FORCEPROP 2 LAST SIG_NAME RMII_PCH_SPRNGVLLE_ARB_IN
J 0
(-1635 2735);
DISPLAY 0.617021 (-1635 2735);
PAINT ORANGE (-1635 2735);
WIRE 68 -1 (-4100 1100)(-3400 1100);
WIRE 68 -1 (-3400 500)(-3400 1100);
WIRE 68 -1 (-4100 500)(-4100 1100);
WIRE 68 -1 (-4100 500)(-3400 500);
WIRE 16 -1 (-6975 350)(-6925 350);
WIRE 16 -1 (-6925 450)(-6925 350);
WIRE 16 -1 (-6075 350)(-6925 350);
FORCEPROP 2 LAST SIG_NAME RST_PLTRST_SPRV_R_N
J 0
(-6660 360);
DISPLAY 0.617021 (-6660 360);
PAINT ORANGE (-6660 360);
WIRE 3 682 (-3200 1975)(-3075 1975);
WIRE 16 -1 (-6325 1675)(-6700 1675);
FORCEPROP 2 LAST SIG_NAME XTAL_25MHZ_IN_R
J 2
(-6325 1685);
DISPLAY 0.617021 (-6325 1685);
PAINT ORANGE (-6325 1685);
WIRE 16 -1 (-6850 2075)(-6250 2075);
FORCEPROP 2 LAST SIG_NAME PE_PCH_SPRV_TX_DN
J 0
(-6760 2085);
DISPLAY 0.617021 (-6760 2085);
PAINT ORANGE (-6760 2085);
WIRE 16 -1 (-7550 350)(-7175 350);
FORCEPROP 2 LAST SIG_NAME RST_PLTRST_N
J 0
(-7510 360);
DISPLAY 0.617021 (-7510 360);
PAINT ORANGE (-7510 360);
WIRE 16 -1 (-6850 2125)(-6025 2125);
FORCEPROP 2 LAST SIG_NAME PE_PCH_SPRV_TX_DP
J 0
(-6760 2135);
DISPLAY 0.617021 (-6760 2135);
PAINT ORANGE (-6760 2135);
WIRE 16 -1 (-3050 1700)(-3050 1600);
WIRE 16 -1 (-3050 1700)(-2400 1700);
FORCEPROP 2 LAST SIG_NAME CLK_50M_CKMNG_SPRVLLE
J 0
(-3010 1710);
DISPLAY 0.617021 (-3010 1710);
PAINT ORANGE (-3010 1710);
WIRE 16 -1 (-6700 1575)(-6325 1575);
FORCEPROP 2 LAST SIG_NAME XTAL_25MHZ_OUT
J 2
(-6325 1585);
DISPLAY 0.617021 (-6325 1585);
PAINT ORANGE (-6325 1585);
WIRE 16 -1 (-3300 2125)(-2500 2125);
FORCEPROP 2 LAST SIG_NAME PE_PCH_SPRV_RX_DP
J 0
(-3210 2135);
DISPLAY 0.617021 (-3210 2135);
PAINT ORANGE (-3210 2135);
FORCEPROP 2 LASTPROP $XRERR UNIQUE?
J 0
(-3450 2135);
DISPLAY 0.638298 (-3450 2135);
PAINT MONO (-3450 2135);
DISPLAY INVISIBLE (-3450 2135);
WIRE 16 -1 (-3300 2375)(-2500 2375);
FORCEPROP 2 LAST SIG_NAME SPI_NIC_MOSI_R
J 0
(-3210 2385);
DISPLAY 0.617021 (-3210 2385);
PAINT ORANGE (-3210 2385);
FORCEPROP 2 LASTPROP $XRERR UNIQUE?
J 0
(-3450 2385);
DISPLAY 0.638298 (-3450 2385);
PAINT MONO (-3450 2385);
DISPLAY INVISIBLE (-3450 2385);
WIRE 16 -1 (-6000 2675)(-5100 2675);
FORCEPROP 2 LAST SIG_NAME RMII_BMC_PCH_SPRNGVLLE_TXEN
J 0
(-6000 2685);
DISPLAY 0.617021 (-6000 2685);
PAINT ORANGE (-6000 2685);
WIRE 16 -1 (-3300 2675)(-2500 2675);
FORCEPROP 2 LAST SIG_NAME RMII_BMC_PCH_SPRNGVLLE_CRSDV_R
J 0
(-3250 2685);
DISPLAY 0.617021 (-3250 2685);
PAINT ORANGE (-3250 2685);
FORCEPROP 2 LASTPROP $XRERR UNIQUE?
J 0
(-3490 2685);
DISPLAY 0.638298 (-3490 2685);
PAINT MONO (-3490 2685);
DISPLAY INVISIBLE (-3490 2685);
WIRE 16 -1 (-5100 2725)(-6000 2725);
FORCEPROP 2 LAST SIG_NAME CLK_50M_CKMNG_SPRVLLE
J 0
(-5985 2735);
DISPLAY 0.617021 (-5985 2735);
PAINT ORANGE (-5985 2735);
WIRE 16 -1 (-6000 2625)(-5100 2625);
FORCEPROP 0 LAST SIG_NAME RMII_PCH_SPRNGVLLE_ARB_OUT
J 0
(-6000 2635);
DISPLAY 0.617021 (-6000 2635);
PAINT ORANGE (-6000 2635);
WIRE 16 -1 (-3300 3825)(-2650 3825);
FORCEPROP 2 LAST SIG_NAME LED_LAN_2_N
J 2
(-2650 3835);
DISPLAY 0.617021 (-2650 3835);
PAINT ORANGE (-2650 3835);
WIRE 16 -1 (-3300 3725)(-2650 3725);
FORCEPROP 2 LAST SIG_NAME LED_LAN_0_N
J 2
(-2650 3735);
DISPLAY 0.617021 (-2650 3735);
PAINT ORANGE (-2650 3735);
WIRE 16 -1 (-2725 3625)(-3300 3625);
FORCEPROP 2 LAST SIG_NAME A_CTOP
J 0
(-3160 3635);
DISPLAY 0.617021 (-3160 3635);
PAINT ORANGE (-3160 3635);
FORCEPROP 2 LASTPROP $XRERR UNIQUE?
J 0
(-3400 3635);
DISPLAY 0.638298 (-3400 3635);
PAINT MONO (-3400 3635);
DISPLAY INVISIBLE (-3400 3635);
WIRE 16 -1 (-2725 3600)(-2725 3625);
WIRE 16 -1 (-2675 4275)(-3300 4275);
FORCEPROP 2 LAST SIG_NAME NIC_SER_P_MDI_3_DP
J 0
(-3185 4285);
DISPLAY 0.617021 (-3185 4285);
PAINT ORANGE (-3185 4285);
WIRE 16 -1 (-2675 4225)(-3300 4225);
FORCEPROP 2 LAST SIG_NAME NIC_SER_N_MDI_3_DN
J 0
(-3185 4235);
DISPLAY 0.617021 (-3185 4235);
PAINT ORANGE (-3185 4235);
WIRE 16 -1 (-2675 4175)(-3300 4175);
FORCEPROP 2 LAST SIG_NAME NIC_SET_P_MDI_2_DP
J 0
(-3185 4185);
DISPLAY 0.617021 (-3185 4185);
PAINT ORANGE (-3185 4185);
WIRE 16 -1 (-2675 4125)(-3300 4125);
FORCEPROP 2 LAST SIG_NAME NIC_SET_N_MDI_2_DN
J 0
(-3185 4135);
DISPLAY 0.617021 (-3185 4135);
PAINT ORANGE (-3185 4135);
WIRE 16 -1 (-2675 4075)(-3300 4075);
FORCEPROP 2 LAST SIG_NAME NIC_MDI_SPRV_RJ45_1_DP
J 0
(-3185 4085);
DISPLAY 0.617021 (-3185 4085);
PAINT ORANGE (-3185 4085);
WIRE 16 -1 (-2675 4025)(-3300 4025);
FORCEPROP 2 LAST SIG_NAME NIC_MDI_SPRV_RJ45_1_DN
J 0
(-3185 4035);
DISPLAY 0.617021 (-3185 4035);
PAINT ORANGE (-3185 4035);
WIRE 16 -1 (-2675 3925)(-3300 3925);
FORCEPROP 2 LAST SIG_NAME NIC_MDI_SPRV_RJ45_0_DN
J 0
(-3185 3935);
DISPLAY 0.617021 (-3185 3935);
PAINT ORANGE (-3185 3935);
WIRE 16 -1 (-2675 3975)(-3300 3975);
FORCEPROP 2 LAST SIG_NAME NIC_MDI_SPRV_RJ45_0_DP
J 0
(-3185 3985);
DISPLAY 0.617021 (-3185 3985);
PAINT ORANGE (-3185 3985);
WIRE 16 -1 (-6050 2075)(-5100 2075);
FORCEPROP 2 LAST SIG_NAME PE_PCH_SPRV_TX_C_DN
J 0
(-5735 2085);
DISPLAY 0.617021 (-5735 2085);
PAINT ORANGE (-5735 2085);
FORCEPROP 2 LASTPROP $XRERR UNIQUE?
J 0
(-5975 2085);
DISPLAY 0.638298 (-5975 2085);
PAINT MONO (-5975 2085);
DISPLAY INVISIBLE (-5975 2085);
WIRE 16 -1 (-6850 2275)(-5100 2275);
FORCEPROP 2 LAST SIG_NAME RST_PLTRST_SPRV_R_N
J 0
(-6785 2285);
DISPLAY 0.617021 (-6785 2285);
PAINT ORANGE (-6785 2285);
WIRE 16 -1 (-5825 2125)(-5100 2125);
FORCEPROP 2 LAST SIG_NAME PE_PCH_SPRV_TX_C_DP
J 0
(-5735 2135);
DISPLAY 0.617021 (-5735 2135);
PAINT ORANGE (-5735 2135);
FORCEPROP 2 LASTPROP $XRERR UNIQUE?
J 0
(-5975 2135);
DISPLAY 0.638298 (-5975 2135);
PAINT MONO (-5975 2135);
DISPLAY INVISIBLE (-5975 2135);
WIRE 16 -1 (-6000 3025)(-5100 3025);
FORCEPROP 2 LAST SIG_NAME PD_SPRV_RSET
J 0
(-6000 3035);
DISPLAY 0.617021 (-6000 3035);
PAINT ORANGE (-6000 3035);
WIRE 3 682 (-1950 3175)(-1950 3300);
WIRE 3 682 (-2050 3175)(-1950 3175);
WIRE 16 -1 (-900 3600)(-375 3600);
WIRE 16 -1 (-900 3725)(-900 3600);
FORCEPROP 2 LAST SIG_NAME PU_SPRV_LAN_PWR_GOOD
J 0
(-885 3610);
DISPLAY 0.617021 (-885 3610);
PAINT ORANGE (-885 3610);
WIRE 16 -1 (-6850 2375)(-5100 2375);
FORCEPROP 2 LAST SIG_NAME SPI_NIC_MISO
J 0
(-6810 2385);
DISPLAY 0.617021 (-6810 2385);
PAINT ORANGE (-6810 2385);
WIRE 16 -1 (-6850 2525)(-5100 2525);
FORCEPROP 2 LAST SIG_NAME RMII_BMC_PCH_SPRNGVLLE_TXD1
J 0
(-6810 2535);
DISPLAY 0.617021 (-6810 2535);
PAINT ORANGE (-6810 2535);
WIRE 16 -1 (-6850 2475)(-5100 2475);
FORCEPROP 2 LAST SIG_NAME RMII_BMC_PCH_SPRNGVLLE_TXD0
J 0
(-6810 2485);
DISPLAY 0.617021 (-6810 2485);
PAINT ORANGE (-6810 2485);
WIRE 16 -1 (-5500 4025)(-5100 4025);
FORCEPROP 0 LAST VOLTAGE 0.9
J 0
(-5475 4100);
DISPLAY 1.021277 (-5475 4100);
PAINT SKYBLUE (-5475 4100);
DISPLAY INVISIBLE (-5475 4100);
FORCEPROP 2 LAST SIG_NAME P0V9_LAN_I210
J 0
(-5485 4035);
DISPLAY 0.617021 (-5485 4035);
PAINT ORANGE (-5485 4035);
FORCEPROP 2 LASTPROP $XRERR UNIQUE?
J 0
(-5725 4035);
DISPLAY 0.638298 (-5725 4035);
PAINT MONO (-5725 4035);
DISPLAY INVISIBLE (-5725 4035);
WIRE 16 -1 (-5700 3875)(-5100 3875);
FORCEPROP 0 LAST VOLTAGE 1.5
J 0
(-5550 3950);
DISPLAY 1.021277 (-5550 3950);
PAINT SKYBLUE (-5550 3950);
DISPLAY INVISIBLE (-5550 3950);
FORCEPROP 2 LAST SIG_NAME P1V5_LAN_I210
J 0
(-5560 3885);
DISPLAY 0.617021 (-5560 3885);
PAINT ORANGE (-5560 3885);
FORCEPROP 2 LASTPROP $XRERR UNIQUE?
J 0
(-5800 3885);
DISPLAY 0.638298 (-5800 3885);
PAINT MONO (-5800 3885);
DISPLAY INVISIBLE (-5800 3885);
WIRE 16 -1 (-3300 2450)(-3300 2475);
WIRE 16 -1 (-3300 2450)(-2000 2450);
FORCEPROP 2 LAST SIG_NAME RMII_SPRNGVLLE_BMC_PCH_RXD0_R
J 0
(-3235 2460);
DISPLAY 0.617021 (-3235 2460);
PAINT ORANGE (-3235 2460);
FORCEPROP 2 LASTPROP $XRERR UNIQUE?
J 0
(-3475 2460);
DISPLAY 0.638298 (-3475 2460);
PAINT MONO (-3475 2460);
DISPLAY INVISIBLE (-3475 2460);
WIRE 16 -1 (-2175 2525)(-750 2525);
FORCEPROP 2 LAST SIG_NAME RMII_SPRNGVLLE_BMC_PCH_RXD1
J 2
(-925 2535);
DISPLAY 0.617021 (-925 2535);
PAINT ORANGE (-925 2535);
WIRE 16 -1 (-2400 3025)(-3300 3025);
FORCEPROP 2 LAST SIG_NAME SMB_SPRINGVILLE_STBY_LVC3_SCL
J 2
(-2375 3035);
DISPLAY 0.617021 (-2375 3035);
PAINT ORANGE (-2375 3035);
WIRE 16 -1 (-2300 2675)(-750 2675);
FORCEPROP 2 LAST SIG_NAME RMII_BMC_PCH_SPRNGVLLE_CRSDV
J 0
(-1635 2685);
DISPLAY 0.617021 (-1635 2685);
PAINT ORANGE (-1635 2685);
WIRE 16 -1 (-5100 2825)(-7750 2825);
FORCEPROP 2 LAST SIG_NAME PU_JTAG_SPRV_TDI
J 0
(-6000 2835);
DISPLAY 0.617021 (-6000 2835);
PAINT ORANGE (-6000 2835);
FORCEPROP 2 LASTPROP $XRERR UNIQUE?
J 0
(-6240 2835);
DISPLAY 0.638298 (-6240 2835);
PAINT MONO (-6240 2835);
DISPLAY INVISIBLE (-6240 2835);
WIRE 16 -1 (-7750 3025)(-7750 2825);
WIRE 16 -1 (-7325 1575)(-6900 1575);
WIRE 16 -1 (-7325 1475)(-7425 1475);
WIRE 16 -1 (-7325 1300)(-7325 1475);
WIRE 16 -1 (-7325 1475)(-7325 1575);
FORCEPROP 2 LAST SIG_NAME XTAL_25MHZ_OUT_R
J 0
(-7335 1585);
DISPLAY 0.617021 (-7335 1585);
PAINT ORANGE (-7335 1585);
FORCEPROP 2 LASTPROP $XRERR UNIQUE?
J 0
(-7575 1585);
DISPLAY 0.638298 (-7575 1585);
PAINT MONO (-7575 1585);
DISPLAY INVISIBLE (-7575 1585);
WIRE 16 3135 (-5875 1775)(-5875 1450);
WIRE 16 3135 (-6325 1775)(-5875 1775);
WIRE 16 3135 (-5875 1450)(-4700 1450);
WIRE 16 3135 (-4700 1450)(-4700 1650);
WIRE 16 3135 (-6325 2200)(-6325 1775);
WIRE 16 3135 (-5375 2200)(-6325 2200);
WIRE 16 3135 (-4700 1650)(-5375 1650);
WIRE 16 3135 (-5375 1650)(-5375 2200);
WIRE 16 -1 (-6850 1925)(-5100 1925);
FORCEPROP 2 LAST SIG_NAME CLK_100M_SPRV_DN
J 0
(-6810 1935);
DISPLAY 0.617021 (-6810 1935);
PAINT ORANGE (-6810 1935);
WIRE 16 -1 (-6850 1975)(-5100 1975);
FORCEPROP 2 LAST SIG_NAME CLK_100M_SPRV_DP
J 0
(-6810 1985);
DISPLAY 0.617021 (-6810 1985);
PAINT ORANGE (-6810 1985);
WIRE 16 -1 (-6850 2225)(-5100 2225);
FORCEPROP 2 LAST SIG_NAME FM_PE_SPRV_WAKE_N
J 0
(-6835 2235);
DISPLAY 0.617021 (-6835 2235);
PAINT ORANGE (-6835 2235);
WIRE 16 -1 (-3300 3775)(-2650 3775);
FORCEPROP 2 LAST SIG_NAME LED_LAN_1_N
J 2
(-2650 3785);
DISPLAY 0.617021 (-2650 3785);
PAINT ORANGE (-2650 3785);
WIRE 16 -1 (-2400 2975)(-3300 2975);
FORCEPROP 2 LAST SIG_NAME SMB_SPRINGVILLE_STBY_LVC3_SDA
J 2
(-2375 2985);
DISPLAY 0.617021 (-2375 2985);
PAINT ORANGE (-2375 2985);
WIRE 16 -1 (-2400 2925)(-3300 2925);
FORCEPROP 2 LAST SIG_NAME IRQ_LOM_ALERT_N
J 2
(-2375 2935);
DISPLAY 0.617021 (-2375 2935);
PAINT ORANGE (-2375 2935);
WIRE 16 -1 (-3300 2825)(-1600 2825);
FORCEPROP 2 LAST SIG_NAME PU_JTAG_SPRV_TDO
J 2
(-2050 2835);
DISPLAY 0.617021 (-2050 2835);
PAINT ORANGE (-2050 2835);
FORCEPROP 2 LASTPROP $XRERR UNIQUE?
J 0
(-2290 2835);
DISPLAY 0.638298 (-2290 2835);
PAINT MONO (-2290 2835);
DISPLAY INVISIBLE (-2290 2835);
WIRE 3 682 (-6850 1350)(-7850 1350);
WIRE 3 682 (-6850 900)(-6850 1350);
WIRE 3 682 (-7850 1350)(-7850 900);
WIRE 3 682 (-7850 900)(-6850 900);
WIRE 68 -1 (-6150 500)(-6150 1100);
WIRE 68 -1 (-6150 1100)(-5500 1100);
WIRE 68 -1 (-6150 500)(-5500 500);
WIRE 68 -1 (-5500 500)(-5500 1100);
WIRE 16 -1 (-5250 3725)(-5700 3725);
FORCEPROP 0 LAST VOLTAGE 3.3
J 0
(-5600 3800);
DISPLAY 1.021277 (-5600 3800);
PAINT SKYBLUE (-5600 3800);
DISPLAY INVISIBLE (-5600 3800);
FORCEPROP 2 LAST SIG_NAME P3V3_STBY_P1V5_LAN_I210
J 0
(-5610 3735);
DISPLAY 0.617021 (-5610 3735);
PAINT ORANGE (-5610 3735);
FORCEPROP 2 LASTPROP $XRERR UNIQUE?
J 0
(-5850 3735);
DISPLAY 0.638298 (-5850 3735);
PAINT MONO (-5850 3735);
DISPLAY INVISIBLE (-5850 3735);
WIRE 16 -1 (-5500 3525)(-5250 3525);
WIRE 16 -1 (-5250 3525)(-5250 3725);
WIRE 16 -1 (-5250 3525)(-5100 3525);
WIRE 16 -1 (-6000 3375)(-5100 3375);
FORCEPROP 2 LAST SIG_NAME XTAL_25MHZ_IN_R
J 0
(-6000 3385);
DISPLAY 0.617021 (-6000 3385);
PAINT ORANGE (-6000 3385);
WIRE 16 -1 (-6000 3225)(-5100 3225);
FORCEPROP 2 LAST SIG_NAME XTAL_25MHZ_OUT
J 0
(-6000 3235);
DISPLAY 0.617021 (-6000 3235);
PAINT ORANGE (-6000 3235);
WIRE 16 -1 (-6000 3075)(-5100 3075);
FORCEPROP 2 LAST SIG_NAME PU_SPRV_LAN_PWR_GOOD
J 0
(-6000 3085);
DISPLAY 0.617021 (-6000 3085);
PAINT ORANGE (-6000 3085);
WIRE 16 -1 (-7200 3025)(-7200 2925);
WIRE 16 -1 (-5100 2925)(-7200 2925);
FORCEPROP 2 LAST SIG_NAME PU_JTAG_SPRV_TCK
J 0
(-6000 2935);
DISPLAY 0.617021 (-6000 2935);
PAINT ORANGE (-6000 2935);
FORCEPROP 2 LASTPROP $XRERR UNIQUE?
J 0
(-6240 2935);
DISPLAY 0.638298 (-6240 2935);
PAINT MONO (-6240 2935);
DISPLAY INVISIBLE (-6240 2935);
WIRE 16 -1 (-7475 3025)(-7475 2875);
WIRE 16 -1 (-5100 2875)(-7475 2875);
FORCEPROP 2 LAST SIG_NAME PU_JTAG_SPRV_TMS
J 0
(-6000 2885);
DISPLAY 0.617021 (-6000 2885);
PAINT ORANGE (-6000 2885);
FORCEPROP 2 LASTPROP $XRERR UNIQUE?
J 0
(-6240 2885);
DISPLAY 0.638298 (-6240 2885);
PAINT MONO (-6240 2885);
DISPLAY INVISIBLE (-6240 2885);
DOT 1 (-5250 3525);
DOT 1 (-1100 675);
DOT 1 (-5725 4125);
DOT 1 (-6375 4150);
DOT 1 (-7750 1475);
DOT 1 (-7325 1475);
DOT 1 (-5725 4225);
DOT 1 (-5725 4275);
DOT 1 (-5725 4425);
DOT 1 (-1600 1050);
DOT 1 (-1350 1050);
DOT 1 (-1100 1050);
DOT 1 (-850 675);
DOT 1 (-600 675);
DOT 1 (-850 1050);
DOT 1 (-2575 600);
DOT 1 (-6925 350);
DOT 1 (-3700 1050);
DOT 1 (-4000 600);
DOT 1 (-3700 600);
DOT 1 (-4700 1050);
DOT 1 (-4950 1050);
DOT 1 (-5200 1050);
DOT 1 (-5450 1050);
DOT 1 (-6100 1050);
DOT 1 (-5800 600);
DOT 1 (-6100 600);
DOT 1 (-600 1050);
DOT 1 (-5800 1050);
DOT 1 (-2825 600);
DOT 1 (-1925 1050);
DOT 1 (-3075 600);
DOT 1 (-3325 600);
DOT 1 (-4700 600);
DOT 1 (-5450 600);
DOT 1 (-5200 600);
DOT 1 (-4950 600);
DOT 1 (-2575 1050);
DOT 1 (-2825 1050);
DOT 1 (-3075 1050);
DOT 1 (-3325 1050);
DOT 1 (-6450 3525);
DOT 1 (-6950 3900);
DOT 1 (-1925 675);
DOT 1 (-1600 675);
DOT 1 (-1350 675);
DOT 1 (-6075 3775);
DOT 1 (-7750 3425);
DOT 1 (-4000 1050);
DOT 1 (-5725 4175);
DOT 1 (-7475 3425);
DOT 1 (-6450 3575);
DOT 1 (-7200 3425);
DOT 1 (-6450 3675);
DOT 1 (-6450 3625);
DOT 1 (-6075 3875);
DOT 1 (-6075 3925);
FORCENOTE
TP FAB3-DVT CHANGE CONNECTION 20161108
(-7925 3725) 0;
DISPLAY LEFT (-7925 3725);
DISPLAY 0.638298 (-7925 3725);
PAINT RED (-7925 3725);
FORCENOTE
ROOM NT_FABRIC
(-7875 225) 0;
DISPLAY LEFT (-7875 225);
DISPLAY 1.212766 (-7875 225);
PAINT PURPLE (-7875 225);
FORCENOTE
TP FAB1 DEL NET 0309
(-3150 1900) 0;
DISPLAY LEFT (-3150 1900);
DISPLAY 1.021277 (-3150 1900);
PAINT RED (-3150 1900);
FORCENOTE
PUT TOGETHER
(-4100 1100) 0;
DISPLAY LEFT (-4100 1100);
DISPLAY 0.808511 (-4100 1100);
PAINT PURPLE (-4100 1100);
FORCENOTE
TP FAB3-DVT ADD RES R9W36 20161114
(-7925 3675) 0;
DISPLAY LEFT (-7925 3675);
DISPLAY 0.638298 (-7925 3675);
PAINT RED (-7925 3675);
FORCENOTE
TP FAB3-DVT CHANGE CONNECTION 20161108
(-1950 3300) 0;
DISPLAY LEFT (-1950 3300);
DISPLAY 0.638298 (-1950 3300);
PAINT RED (-1950 3300);
FORCENOTE
TP FAB3 CHANGE CAP 0902
(-7175 1350) 0;
DISPLAY LEFT (-7175 1350);
DISPLAY 0.638298 (-7175 1350);
PAINT RED (-7175 1350);
FORCENOTE
TP FAB1 CHANGE ONE 100UF CPA TO FOUR 22UF CAPS 0108
(-3900 425) 0;
DISPLAY LEFT (-3900 425);
DISPLAY 1.021277 (-3900 425);
PAINT RED (-3900 425);
FORCENOTE
TP FAB1 CHANGE ONE 100UF CPA TO FOUR 22UF CAPS 0108
(-6075 425) 0;
DISPLAY LEFT (-6075 425);
DISPLAY 1.021277 (-6075 425);
PAINT RED (-6075 425);
FORCENOTE
PUT TOGETHER
(-6150 1100) 0;
DISPLAY LEFT (-6150 1100);
DISPLAY 0.808511 (-6150 1100);
PAINT PURPLE (-6150 1100);
QUIT
